G04 ================== begin FILE IDENTIFICATION RECORD ==================*
G04 Layout Name:  D:/<user>/Wistron_project/16317-1/gbr/16317-1.brd*
G04 Film Name:    L8*
G04 File Format:  Gerber RS274X*
G04 File Origin:  Cadence Allegro 16.5-S056*
G04 Origin Date:  Fri Jun 09 15:53:46 2017*
G04 *
G04 Layer:  VIA CLASS/BOTTOM*
G04 Layer:  PIN/BOTTOM*
G04 Layer:  ETCH/BOTTOM*
G04 Layer:  DRAWING FORMAT/LAYER_PCB_STORY*
G04 Layer:  DRAWING FORMAT/LAYER_L8*
G04 *
G04 Offset:    (0.00 0.00)*
G04 Mirror:    No*
G04 Mode:      Positive*
G04 Rotation:  0*
G04 FullContactRelief:  No*
G04 UndefLineWidth:     6.00*
G04 ================== end FILE IDENTIFICATION RECORD ====================*
%FSLAX35Y35*MOIN*%
%IR0*IPPOS*OFA0.00000B0.00000*MIA0B0*SFA1.00000B1.00000*%
%AMMACRO50*
4,1,40,.011,.007,
.011,-.007,
.010939,-.007695,
.010759,-.008368,
.010464,-.009,
.010064,-.009571,
.009571,-.010064,
.009,-.010464,
.008368,-.010759,
.007695,-.010939,
.007,-.011,
-.007,-.011,
-.007695,-.010939,
-.008368,-.010759,
-.009,-.010464,
-.009571,-.010064,
-.010064,-.009571,
-.010464,-.009,
-.010759,-.008368,
-.010939,-.007695,
-.011,-.007,
-.011,.007,
-.010939,.007695,
-.010759,.008368,
-.010464,.009,
-.010064,.009571,
-.009571,.010064,
-.009,.010464,
-.008368,.010759,
-.007695,.010939,
-.007,.011,
.007,.011,
.007695,.010939,
.008368,.010759,
.009,.010464,
.009571,.010064,
.010064,.009571,
.010464,.009,
.010759,.008368,
.010939,.007695,
.011,.007,
0.0*
%
%ADD50MACRO50*%
%AMMACRO41*
4,1,40,.013,-.017,
-.013,-.017,
-.013695,-.016939,
-.014368,-.016759,
-.015,-.016464,
-.015571,-.016064,
-.016064,-.015571,
-.016464,-.015,
-.016759,-.014368,
-.016939,-.013695,
-.017,-.013,
-.017,.013,
-.016939,.013695,
-.016759,.014368,
-.016464,.015,
-.016064,.015571,
-.015571,.016064,
-.015,.016464,
-.014368,.016759,
-.013695,.016939,
-.013,.017,
.013,.017,
.013695,.016939,
.014368,.016759,
.015,.016464,
.015571,.016064,
.016064,.015571,
.016464,.015,
.016759,.014368,
.016939,.013695,
.017,.013,
.017,-.013,
.016939,-.013695,
.016759,-.014368,
.016464,-.015,
.016064,-.015571,
.015571,-.016064,
.015,-.016464,
.014368,-.016759,
.013695,-.016939,
.013,-.017,
0.0*
%
%ADD41MACRO41*%
%AMMACRO25*
4,1,40,-.017,-.013,
-.017,.013,
-.016939,.013695,
-.016759,.014368,
-.016464,.015,
-.016064,.015571,
-.015571,.016064,
-.015,.016464,
-.014368,.016759,
-.013695,.016939,
-.013,.017,
.013,.017,
.013695,.016939,
.014368,.016759,
.015,.016464,
.015571,.016064,
.016064,.015571,
.016464,.015,
.016759,.014368,
.016939,.013695,
.017,.013,
.017,-.013,
.016939,-.013695,
.016759,-.014368,
.016464,-.015,
.016064,-.015571,
.015571,-.016064,
.015,-.016464,
.014368,-.016759,
.013695,-.016939,
.013,-.017,
-.013,-.017,
-.013695,-.016939,
-.014368,-.016759,
-.015,-.016464,
-.015571,-.016064,
-.016064,-.015571,
-.016464,-.015,
-.016759,-.014368,
-.016939,-.013695,
-.017,-.013,
0.0*
%
%ADD25MACRO25*%
%ADD44R,.01X.007*%
%ADD11C,.01*%
%ADD34C,.02*%
%ADD53C,.03*%
%ADD12C,.022*%
%ADD10C,.04*%
%ADD63C,.032*%
%ADD33C,.05*%
%ADD32C,.024*%
%ADD46C,.034*%
%ADD54C,.026*%
%ADD13C,.028*%
%ADD45C,.056*%
%ADD60C,.048*%
%AMMACRO48*
4,1,40,.007,-.0225,
.008389,-.022378,
.009736,-.022018,
.011,-.021428,
.012142,-.020628,
.013128,-.019642,
.013928,-.0185,
.014518,-.017236,
.014878,-.015889,
.015,-.0145,
.015,.0145,
.014878,.015889,
.014518,.017236,
.013928,.0185,
.013128,.019642,
.012142,.020628,
.011,.021428,
.009736,.022018,
.008389,.022378,
.007,.0225,
-.007,.0225,
-.008389,.022378,
-.009736,.022018,
-.011,.021428,
-.012142,.020628,
-.013128,.019642,
-.013928,.0185,
-.014518,.017236,
-.014878,.015889,
-.015,.0145,
-.015,-.0145,
-.014878,-.015889,
-.014518,-.017236,
-.013928,-.0185,
-.013128,-.019642,
-.012142,-.020628,
-.011,-.021428,
-.009736,-.022018,
-.008389,-.022378,
-.007,-.0225,
.007,-.0225,
0.0*
%
%ADD48MACRO48*%
%ADD67R,.066X.066*%
%AMMACRO61*
4,1,40,.007,-.011,
-.007,-.011,
-.007695,-.010939,
-.008368,-.010759,
-.009,-.010464,
-.009571,-.010064,
-.010064,-.009571,
-.010464,-.009,
-.010759,-.008368,
-.010939,-.007695,
-.011,-.007,
-.011,.007,
-.010939,.007695,
-.010759,.008368,
-.010464,.009,
-.010064,.009571,
-.009571,.010064,
-.009,.010464,
-.008368,.010759,
-.007695,.010939,
-.007,.011,
.007,.011,
.007695,.010939,
.008368,.010759,
.009,.010464,
.009571,.010064,
.010064,.009571,
.010464,.009,
.010759,.008368,
.010939,.007695,
.011,.007,
.011,-.007,
.010939,-.007695,
.010759,-.008368,
.010464,-.009,
.010064,-.009571,
.009571,-.010064,
.009,-.010464,
.008368,-.010759,
.007695,-.010939,
.007,-.011,
0.0*
%
%ADD61MACRO61*%
%AMMACRO18*
4,1,40,-.011,-.007,
-.011,.007,
-.010939,.007695,
-.010759,.008368,
-.010464,.009,
-.010064,.009571,
-.009571,.010064,
-.009,.010464,
-.008368,.010759,
-.007695,.010939,
-.007,.011,
.007,.011,
.007695,.010939,
.008368,.010759,
.009,.010464,
.009571,.010064,
.010064,.009571,
.010464,.009,
.010759,.008368,
.010939,.007695,
.011,.007,
.011,-.007,
.010939,-.007695,
.010759,-.008368,
.010464,-.009,
.010064,-.009571,
.009571,-.010064,
.009,-.010464,
.008368,-.010759,
.007695,-.010939,
.007,-.011,
-.007,-.011,
-.007695,-.010939,
-.008368,-.010759,
-.009,-.010464,
-.009571,-.010064,
-.010064,-.009571,
-.010464,-.009,
-.010759,-.008368,
-.010939,-.007695,
-.011,-.007,
0.0*
%
%ADD18MACRO18*%
%AMMACRO17*
4,1,40,-.012,-.008,
-.012,.008,
-.011939,.008695,
-.011759,.009368,
-.011464,.01,
-.011064,.010571,
-.010571,.011064,
-.01,.011464,
-.009368,.011759,
-.008695,.011939,
-.008,.012,
.008,.012,
.008695,.011939,
.009368,.011759,
.01,.011464,
.010571,.011064,
.011064,.010571,
.011464,.01,
.011759,.009368,
.011939,.008695,
.012,.008,
.012,-.008,
.011939,-.008695,
.011759,-.009368,
.011464,-.01,
.011064,-.010571,
.010571,-.011064,
.01,-.011464,
.009368,-.011759,
.008695,-.011939,
.008,-.012,
-.008,-.012,
-.008695,-.011939,
-.009368,-.011759,
-.01,-.011464,
-.010571,-.011064,
-.011064,-.010571,
-.011464,-.01,
-.011759,-.009368,
-.011939,-.008695,
-.012,-.008,
0.0*
%
%ADD17MACRO17*%
%AMMACRO52*
4,1,40,-.008,.012,
.008,.012,
.008695,.011939,
.009368,.011759,
.01,.011464,
.010571,.011064,
.011064,.010571,
.011464,.01,
.011759,.009368,
.011939,.008695,
.012,.008,
.012,-.008,
.011939,-.008695,
.011759,-.009368,
.011464,-.01,
.011064,-.010571,
.010571,-.011064,
.01,-.011464,
.009368,-.011759,
.008695,-.011939,
.008,-.012,
-.008,-.012,
-.008695,-.011939,
-.009368,-.011759,
-.01,-.011464,
-.010571,-.011064,
-.011064,-.010571,
-.011464,-.01,
-.011759,-.009368,
-.011939,-.008695,
-.012,-.008,
-.012,.008,
-.011939,.008695,
-.011759,.009368,
-.011464,.01,
-.011064,.010571,
-.010571,.011064,
-.01,.011464,
-.009368,.011759,
-.008695,.011939,
-.008,.012,
0.0*
%
%ADD52MACRO52*%
%AMMACRO22*
4,1,40,-.013,.017,
.013,.017,
.013695,.016939,
.014368,.016759,
.015,.016464,
.015571,.016064,
.016064,.015571,
.016464,.015,
.016759,.014368,
.016939,.013695,
.017,.013,
.017,-.013,
.016939,-.013695,
.016759,-.014368,
.016464,-.015,
.016064,-.015571,
.015571,-.016064,
.015,-.016464,
.014368,-.016759,
.013695,-.016939,
.013,-.017,
-.013,-.017,
-.013695,-.016939,
-.014368,-.016759,
-.015,-.016464,
-.015571,-.016064,
-.016064,-.015571,
-.016464,-.015,
-.016759,-.014368,
-.016939,-.013695,
-.017,-.013,
-.017,.013,
-.016939,.013695,
-.016759,.014368,
-.016464,.015,
-.016064,.015571,
-.015571,.016064,
-.015,.016464,
-.014368,.016759,
-.013695,.016939,
-.013,.017,
0.0*
%
%ADD22MACRO22*%
%AMMACRO64*
4,1,40,.017,.013,
.017,-.013,
.016939,-.013695,
.016759,-.014368,
.016464,-.015,
.016064,-.015571,
.015571,-.016064,
.015,-.016464,
.014368,-.016759,
.013695,-.016939,
.013,-.017,
-.013,-.017,
-.013695,-.016939,
-.014368,-.016759,
-.015,-.016464,
-.015571,-.016064,
-.016064,-.015571,
-.016464,-.015,
-.016759,-.014368,
-.016939,-.013695,
-.017,-.013,
-.017,.013,
-.016939,.013695,
-.016759,.014368,
-.016464,.015,
-.016064,.015571,
-.015571,.016064,
-.015,.016464,
-.014368,.016759,
-.013695,.016939,
-.013,.017,
.013,.017,
.013695,.016939,
.014368,.016759,
.015,.016464,
.015571,.016064,
.016064,.015571,
.016464,.015,
.016759,.014368,
.016939,.013695,
.017,.013,
0.0*
%
%ADD64MACRO64*%
%AMMACRO29*
4,1,6,.025,-.0135,
.005,.0065,
.005,.0135,
-.005,.0135,
-.005,.0065,
-.025,-.0135,
.025,-.0135,
0.0*
%
%ADD29MACRO29*%
%AMMACRO62*
4,1,40,.007,-.011,
-.007,-.011,
-.007695,-.010939,
-.008368,-.010759,
-.009,-.010464,
-.009571,-.010064,
-.010064,-.009571,
-.010464,-.009,
-.010759,-.008368,
-.010939,-.007695,
-.011,-.007,
-.011,.007,
-.010939,.007695,
-.010759,.008368,
-.010464,.009,
-.010064,.009571,
-.009571,.010064,
-.009,.010464,
-.008368,.010759,
-.007695,.010939,
-.007,.011,
.007,.011,
.007695,.010939,
.008368,.010759,
.009,.010464,
.009571,.010064,
.010064,.009571,
.010464,.009,
.010759,.008368,
.010939,.007695,
.011,.007,
.011,-.007,
.010939,-.007695,
.010759,-.008368,
.010464,-.009,
.010064,-.009571,
.009571,-.010064,
.009,-.010464,
.008368,-.010759,
.007695,-.010939,
.007,-.011,
0.0*
%
%ADD62MACRO62*%
%AMMACRO19*
4,1,40,-.011,-.007,
-.011,.007,
-.010939,.007695,
-.010759,.008368,
-.010464,.009,
-.010064,.009571,
-.009571,.010064,
-.009,.010464,
-.008368,.010759,
-.007695,.010939,
-.007,.011,
.007,.011,
.007695,.010939,
.008368,.010759,
.009,.010464,
.009571,.010064,
.010064,.009571,
.010464,.009,
.010759,.008368,
.010939,.007695,
.011,.007,
.011,-.007,
.010939,-.007695,
.010759,-.008368,
.010464,-.009,
.010064,-.009571,
.009571,-.010064,
.009,-.010464,
.008368,-.010759,
.007695,-.010939,
.007,-.011,
-.007,-.011,
-.007695,-.010939,
-.008368,-.010759,
-.009,-.010464,
-.009571,-.010064,
-.010064,-.009571,
-.010464,-.009,
-.010759,-.008368,
-.010939,-.007695,
-.011,-.007,
0.0*
%
%ADD19MACRO19*%
%AMMACRO16*
4,1,40,-.012,-.008,
-.012,.008,
-.011939,.008695,
-.011759,.009368,
-.011464,.01,
-.011064,.010571,
-.010571,.011064,
-.01,.011464,
-.009368,.011759,
-.008695,.011939,
-.008,.012,
.008,.012,
.008695,.011939,
.009368,.011759,
.01,.011464,
.010571,.011064,
.011064,.010571,
.011464,.01,
.011759,.009368,
.011939,.008695,
.012,.008,
.012,-.008,
.011939,-.008695,
.011759,-.009368,
.011464,-.01,
.011064,-.010571,
.010571,-.011064,
.01,-.011464,
.009368,-.011759,
.008695,-.011939,
.008,-.012,
-.008,-.012,
-.008695,-.011939,
-.009368,-.011759,
-.01,-.011464,
-.010571,-.011064,
-.011064,-.010571,
-.011464,-.01,
-.011759,-.009368,
-.011939,-.008695,
-.012,-.008,
0.0*
%
%ADD16MACRO16*%
%AMMACRO51*
4,1,40,-.008,.012,
.008,.012,
.008695,.011939,
.009368,.011759,
.01,.011464,
.010571,.011064,
.011064,.010571,
.011464,.01,
.011759,.009368,
.011939,.008695,
.012,.008,
.012,-.008,
.011939,-.008695,
.011759,-.009368,
.011464,-.01,
.011064,-.010571,
.010571,-.011064,
.01,-.011464,
.009368,-.011759,
.008695,-.011939,
.008,-.012,
-.008,-.012,
-.008695,-.011939,
-.009368,-.011759,
-.01,-.011464,
-.010571,-.011064,
-.011064,-.010571,
-.011464,-.01,
-.011759,-.009368,
-.011939,-.008695,
-.012,-.008,
-.012,.008,
-.011939,.008695,
-.011759,.009368,
-.011464,.01,
-.011064,.010571,
-.010571,.011064,
-.01,.011464,
-.009368,.011759,
-.008695,.011939,
-.008,.012,
0.0*
%
%ADD51MACRO51*%
%AMMACRO23*
4,1,40,-.013,.017,
.013,.017,
.013695,.016939,
.014368,.016759,
.015,.016464,
.015571,.016064,
.016064,.015571,
.016464,.015,
.016759,.014368,
.016939,.013695,
.017,.013,
.017,-.013,
.016939,-.013695,
.016759,-.014368,
.016464,-.015,
.016064,-.015571,
.015571,-.016064,
.015,-.016464,
.014368,-.016759,
.013695,-.016939,
.013,-.017,
-.013,-.017,
-.013695,-.016939,
-.014368,-.016759,
-.015,-.016464,
-.015571,-.016064,
-.016064,-.015571,
-.016464,-.015,
-.016759,-.014368,
-.016939,-.013695,
-.017,-.013,
-.017,.013,
-.016939,.013695,
-.016759,.014368,
-.016464,.015,
-.016064,.015571,
-.015571,.016064,
-.015,.016464,
-.014368,.016759,
-.013695,.016939,
-.013,.017,
0.0*
%
%ADD23MACRO23*%
%AMMACRO65*
4,1,40,.017,.013,
.017,-.013,
.016939,-.013695,
.016759,-.014368,
.016464,-.015,
.016064,-.015571,
.015571,-.016064,
.015,-.016464,
.014368,-.016759,
.013695,-.016939,
.013,-.017,
-.013,-.017,
-.013695,-.016939,
-.014368,-.016759,
-.015,-.016464,
-.015571,-.016064,
-.016064,-.015571,
-.016464,-.015,
-.016759,-.014368,
-.016939,-.013695,
-.017,-.013,
-.017,.013,
-.016939,.013695,
-.016759,.014368,
-.016464,.015,
-.016064,.015571,
-.015571,.016064,
-.015,.016464,
-.014368,.016759,
-.013695,.016939,
-.013,.017,
.013,.017,
.013695,.016939,
.014368,.016759,
.015,.016464,
.015571,.016064,
.016064,.015571,
.016464,.015,
.016759,.014368,
.016939,.013695,
.017,.013,
0.0*
%
%ADD65MACRO65*%
%ADD57R,.2X.208*%
%ADD56R,.001X.001*%
%ADD58R,.06X.03*%
%ADD47R,.022X.04*%
%ADD43C,.101*%
%ADD31R,.044X.012*%
%ADD70R,.036X.012*%
%ADD68R,.012X.036*%
%ADD42R,.14X.138*%
%ADD71R,.037X.012*%
%ADD69R,.012X.037*%
%ADD59R,.115X.138*%
%ADD66R,.05X.065*%
%ADD27R,.045X.055*%
%ADD26R,.055X.045*%
%ADD55R,.083X.057*%
%ADD37R,.095X.09*%
%ADD35C,.375*%
%ADD36O,.552X.788*%
%AMMACRO39*
4,1,40,.012,.008,
.012,-.008,
.011939,-.008695,
.011759,-.009368,
.011464,-.01,
.011064,-.010571,
.010571,-.011064,
.01,-.011464,
.009368,-.011759,
.008695,-.011939,
.008,-.012,
-.008,-.012,
-.008695,-.011939,
-.009368,-.011759,
-.01,-.011464,
-.010571,-.011064,
-.011064,-.010571,
-.011464,-.01,
-.011759,-.009368,
-.011939,-.008695,
-.012,-.008,
-.012,.008,
-.011939,.008695,
-.011759,.009368,
-.011464,.01,
-.011064,.010571,
-.010571,.011064,
-.01,.011464,
-.009368,.011759,
-.008695,.011939,
-.008,.012,
.008,.012,
.008695,.011939,
.009368,.011759,
.01,.011464,
.010571,.011064,
.011064,.010571,
.011464,.01,
.011759,.009368,
.011939,.008695,
.012,.008,
0.0*
%
%ADD39MACRO39*%
%AMMACRO20*
4,1,40,-.007,.011,
.007,.011,
.007695,.010939,
.008368,.010759,
.009,.010464,
.009571,.010064,
.010064,.009571,
.010464,.009,
.010759,.008368,
.010939,.007695,
.011,.007,
.011,-.007,
.010939,-.007695,
.010759,-.008368,
.010464,-.009,
.010064,-.009571,
.009571,-.010064,
.009,-.010464,
.008368,-.010759,
.007695,-.010939,
.007,-.011,
-.007,-.011,
-.007695,-.010939,
-.008368,-.010759,
-.009,-.010464,
-.009571,-.010064,
-.010064,-.009571,
-.010464,-.009,
-.010759,-.008368,
-.010939,-.007695,
-.011,-.007,
-.011,.007,
-.010939,.007695,
-.010759,.008368,
-.010464,.009,
-.010064,.009571,
-.009571,.010064,
-.009,.010464,
-.008368,.010759,
-.007695,.010939,
-.007,.011,
0.0*
%
%ADD20MACRO20*%
%AMMACRO15*
4,1,40,.008,-.012,
-.008,-.012,
-.008695,-.011939,
-.009368,-.011759,
-.01,-.011464,
-.010571,-.011064,
-.011064,-.010571,
-.011464,-.01,
-.011759,-.009368,
-.011939,-.008695,
-.012,-.008,
-.012,.008,
-.011939,.008695,
-.011759,.009368,
-.011464,.01,
-.011064,.010571,
-.010571,.011064,
-.01,.011464,
-.009368,.011759,
-.008695,.011939,
-.008,.012,
.008,.012,
.008695,.011939,
.009368,.011759,
.01,.011464,
.010571,.011064,
.011064,.010571,
.011464,.01,
.011759,.009368,
.011939,.008695,
.012,.008,
.012,-.008,
.011939,-.008695,
.011759,-.009368,
.011464,-.01,
.011064,-.010571,
.010571,-.011064,
.01,-.011464,
.009368,-.011759,
.008695,-.011939,
.008,-.012,
0.0*
%
%ADD15MACRO15*%
%AMMACRO49*
4,1,40,.011,.007,
.011,-.007,
.010939,-.007695,
.010759,-.008368,
.010464,-.009,
.010064,-.009571,
.009571,-.010064,
.009,-.010464,
.008368,-.010759,
.007695,-.010939,
.007,-.011,
-.007,-.011,
-.007695,-.010939,
-.008368,-.010759,
-.009,-.010464,
-.009571,-.010064,
-.010064,-.009571,
-.010464,-.009,
-.010759,-.008368,
-.010939,-.007695,
-.011,-.007,
-.011,.007,
-.010939,.007695,
-.010759,.008368,
-.010464,.009,
-.010064,.009571,
-.009571,.010064,
-.009,.010464,
-.008368,.010759,
-.007695,.010939,
-.007,.011,
.007,.011,
.007695,.010939,
.008368,.010759,
.009,.010464,
.009571,.010064,
.010064,.009571,
.010464,.009,
.010759,.008368,
.010939,.007695,
.011,.007,
0.0*
%
%ADD49MACRO49*%
%AMMACRO40*
4,1,40,.013,-.017,
-.013,-.017,
-.013695,-.016939,
-.014368,-.016759,
-.015,-.016464,
-.015571,-.016064,
-.016064,-.015571,
-.016464,-.015,
-.016759,-.014368,
-.016939,-.013695,
-.017,-.013,
-.017,.013,
-.016939,.013695,
-.016759,.014368,
-.016464,.015,
-.016064,.015571,
-.015571,.016064,
-.015,.016464,
-.014368,.016759,
-.013695,.016939,
-.013,.017,
.013,.017,
.013695,.016939,
.014368,.016759,
.015,.016464,
.015571,.016064,
.016064,.015571,
.016464,.015,
.016759,.014368,
.016939,.013695,
.017,.013,
.017,-.013,
.016939,-.013695,
.016759,-.014368,
.016464,-.015,
.016064,-.015571,
.015571,-.016064,
.015,-.016464,
.014368,-.016759,
.013695,-.016939,
.013,-.017,
0.0*
%
%ADD40MACRO40*%
%AMMACRO24*
4,1,40,-.017,-.013,
-.017,.013,
-.016939,.013695,
-.016759,.014368,
-.016464,.015,
-.016064,.015571,
-.015571,.016064,
-.015,.016464,
-.014368,.016759,
-.013695,.016939,
-.013,.017,
.013,.017,
.013695,.016939,
.014368,.016759,
.015,.016464,
.015571,.016064,
.016064,.015571,
.016464,.015,
.016759,.014368,
.016939,.013695,
.017,.013,
.017,-.013,
.016939,-.013695,
.016759,-.014368,
.016464,-.015,
.016064,-.015571,
.015571,-.016064,
.015,-.016464,
.014368,-.016759,
.013695,-.016939,
.013,-.017,
-.013,-.017,
-.013695,-.016939,
-.014368,-.016759,
-.015,-.016464,
-.015571,-.016064,
-.016064,-.015571,
-.016464,-.015,
-.016759,-.014368,
-.016939,-.013695,
-.017,-.013,
0.0*
%
%ADD24MACRO24*%
%AMMACRO30*
4,1,20,-.0655,-.1095,
-.051,-.1095,
-.051,-.12,
-.0375,-.12,
-.0375,-.1095,
.0375,-.1095,
.0375,-.12,
.051,-.12,
.051,-.1095,
.0655,-.1095,
.0655,.1095,
.051,.1095,
.051,.12,
.0375,.12,
.0375,.1095,
-.0375,.1095,
-.0375,.12,
-.051,.12,
-.051,.1095,
-.0655,.1095,
-.0655,-.1095,
0.0*
%
%ADD30MACRO30*%
%AMMACRO28*
4,1,6,.005,-.0135,
.005,-.0065,
.025,.0135,
-.025,.0135,
-.005,-.0065,
-.005,-.0135,
.005,-.0135,
0.0*
%
%ADD28MACRO28*%
%AMMACRO38*
4,1,40,.012,.008,
.012,-.008,
.011939,-.008695,
.011759,-.009368,
.011464,-.01,
.011064,-.010571,
.010571,-.011064,
.01,-.011464,
.009368,-.011759,
.008695,-.011939,
.008,-.012,
-.008,-.012,
-.008695,-.011939,
-.009368,-.011759,
-.01,-.011464,
-.010571,-.011064,
-.011064,-.010571,
-.011464,-.01,
-.011759,-.009368,
-.011939,-.008695,
-.012,-.008,
-.012,.008,
-.011939,.008695,
-.011759,.009368,
-.011464,.01,
-.011064,.010571,
-.010571,.011064,
-.01,.011464,
-.009368,.011759,
-.008695,.011939,
-.008,.012,
.008,.012,
.008695,.011939,
.009368,.011759,
.01,.011464,
.010571,.011064,
.011064,.010571,
.011464,.01,
.011759,.009368,
.011939,.008695,
.012,.008,
0.0*
%
%ADD38MACRO38*%
%AMMACRO21*
4,1,40,-.007,.011,
.007,.011,
.007695,.010939,
.008368,.010759,
.009,.010464,
.009571,.010064,
.010064,.009571,
.010464,.009,
.010759,.008368,
.010939,.007695,
.011,.007,
.011,-.007,
.010939,-.007695,
.010759,-.008368,
.010464,-.009,
.010064,-.009571,
.009571,-.010064,
.009,-.010464,
.008368,-.010759,
.007695,-.010939,
.007,-.011,
-.007,-.011,
-.007695,-.010939,
-.008368,-.010759,
-.009,-.010464,
-.009571,-.010064,
-.010064,-.009571,
-.010464,-.009,
-.010759,-.008368,
-.010939,-.007695,
-.011,-.007,
-.011,.007,
-.010939,.007695,
-.010759,.008368,
-.010464,.009,
-.010064,.009571,
-.009571,.010064,
-.009,.010464,
-.008368,.010759,
-.007695,.010939,
-.007,.011,
0.0*
%
%ADD21MACRO21*%
%AMMACRO14*
4,1,40,.008,-.012,
-.008,-.012,
-.008695,-.011939,
-.009368,-.011759,
-.01,-.011464,
-.010571,-.011064,
-.011064,-.010571,
-.011464,-.01,
-.011759,-.009368,
-.011939,-.008695,
-.012,-.008,
-.012,.008,
-.011939,.008695,
-.011759,.009368,
-.011464,.01,
-.011064,.010571,
-.010571,.011064,
-.01,.011464,
-.009368,.011759,
-.008695,.011939,
-.008,.012,
.008,.012,
.008695,.011939,
.009368,.011759,
.01,.011464,
.010571,.011064,
.011064,.010571,
.011464,.01,
.011759,.009368,
.011939,.008695,
.012,.008,
.012,-.008,
.011939,-.008695,
.011759,-.009368,
.011464,-.01,
.011064,-.010571,
.010571,-.011064,
.01,-.011464,
.009368,-.011759,
.008695,-.011939,
.008,-.012,
0.0*
%
%ADD14MACRO14*%
%ADD72C,.012*%
%ADD73C,.06*%
%ADD74C,.015*%
%ADD75C,.006*%
%ADD76C,.005*%
%ADD77C,.0065*%
%ADD78C,.00675*%
%ADD81C,.04604*%
%ADD79C,.3222*%
%ADD80R,.008X.008*%
G75*
%LPD*%
G75*
G36*
G01X701235Y483821D02*
X587400Y409895D01*
X579417D01*
G03X569014Y413706I-10403J-12293D01*
G01X564014D01*
G03X562466Y413631I5J-16106D01*
G03X556847Y415578I-7991J-13980D01*
G03X546243Y416503I-6623J-14678D01*
G03X527697Y396482I-3001J-15821D01*
G01X527704Y396456D01*
Y389927D01*
G03X524564Y373857I12039J-10694D01*
G01X524575Y373825D01*
Y369095D01*
X505387Y356634D01*
X443320Y261061D01*
X426796D01*
X421835Y266022D01*
Y274781D01*
G03X336629I-42603J0D01*
G01Y200317D01*
G03X328587Y181335I7371J-14317D01*
G01X328596Y181306D01*
Y176118D01*
G03X321856Y166517I8904J-13417D01*
G01X321837Y166440D01*
X304548Y155212D01*
X304449Y155255D01*
G03X281897Y140609I-6449J-14755D01*
G01X281896Y140502D01*
X266657Y130605D01*
X266542Y130725D01*
G03X252501Y135523I-11642J-11125D01*
G03X251175Y135601I-1608J-16023D01*
G03X248274Y141319I-15526J-4282D01*
G03X251755Y151319I-12625J10001D01*
G01Y161319D01*
G03X250827Y166706I-16106J-1D01*
G01Y179850D01*
G03X252878Y187504I-15591J8280D01*
G03X227002Y203745I-10229J12437D01*
G03X223747Y201533I8233J-15616D01*
G03X203876Y182101I-4247J-15533D01*
G01X203882Y182077D01*
Y175615D01*
G03X198054Y158143I9617J-12916D01*
G01X192547Y152636D01*
X184085D01*
G03X158062Y135919I-10585J-12136D01*
G03X156254Y110457I15166J-13872D01*
G01Y92359D01*
X152828Y90134D01*
X152825D01*
X148828Y87536D01*
X148019Y87010D01*
X147161Y86453D01*
X142773D01*
G03X140387Y90442I-14784J-6135D01*
G01Y98596D01*
X146458Y104667D01*
Y112852D01*
X146473Y112927D01*
Y112929D01*
G03X136615Y134402I-14873J6171D01*
G01X126925Y144092D01*
Y146901D01*
X126933Y146928D01*
G03X127543Y151318I-15496J4391D01*
G01Y161319D01*
G03X126926Y165734I-16106J0D01*
G01Y180464D01*
G03X128666Y187504I-15902J7665D01*
G03X134455Y198290I-10229J12437D01*
G01X134462Y198360D01*
X148233Y212131D01*
G03X173803Y251181I-17033J39050D01*
G01Y274781D01*
G03X88597I-42603J0D01*
G01Y220332D01*
X92845Y216084D01*
Y204369D01*
X89364Y200888D01*
G03X79762Y182590I6136J-14888D01*
G01X79767Y182569D01*
Y175893D01*
G03X92884Y147072I9234J-13193D01*
G01X92908Y147078D01*
X95900D01*
G03X98812Y141319I15537J4241D01*
G03X95331Y131319I12625J-10001D01*
G01Y121319D01*
G03X96429Y115474I16106J0D01*
G03X90845Y103926I10508J-12205D01*
G02X90410Y103544I-400J16D01*
G03X89000Y103606I-1412J-16044D01*
G01X80865D01*
X79944Y104527D01*
Y105532D01*
X80329Y105917D01*
X80360Y105932D01*
G03X88021Y127461I-6860J14569D01*
G03X67832Y148285I-15121J5539D01*
G01X67801Y148275D01*
X63602D01*
G03X33973Y136231I-14102J-7775D01*
G01Y107096D01*
X33972Y107086D01*
G03X44704Y90289I16028J-1586D01*
G01Y86706D01*
X39829Y81831D01*
X36774D01*
X36737Y81847D01*
G03X23001Y81250I-6236J-14847D01*
G03X16263Y74525I7498J-14251D01*
G01X16249Y74498D01*
X8000Y66249D01*
Y8000D01*
X58659D01*
X64697Y14038D01*
X64746Y14052D01*
G03X76147Y23001I-5346J18548D01*
G03X75144Y43769I-16747J9599D01*
G01X75107Y43821D01*
Y45544D01*
X76817Y47254D01*
X83145D01*
X94579Y35820D01*
G03X102574Y24926I16445J3688D01*
G03X103034Y23001I15863J2773D01*
G01Y8000D01*
X258052D01*
Y23001D01*
G03X258272Y31601I-15403J4697D01*
G01X258244Y31711D01*
X264050Y37517D01*
X264096Y37532D01*
G03X273271Y45150I-4901J15237D01*
G01X273315Y45231D01*
X274433Y45467D01*
X281852Y50283D01*
X296482D01*
G03X309747Y51523I5268J15217D01*
G01X331263D01*
G03X340149Y47682I10537J12177D01*
G01X340220Y47675D01*
X343362Y44533D01*
X343327Y44418D01*
G03X350999Y24926I16122J-4910D01*
G03X351459Y23001I15863J2773D01*
G01Y8000D01*
X382265D01*
Y23001D01*
G03X382744Y30354I-15403J4696D01*
G01X382727Y30455D01*
X390893Y38621D01*
X390920Y38635D01*
G03X398346Y47021I-7513J14133D01*
G01X398369Y47081D01*
X402079Y49491D01*
X406349Y56073D01*
X406987Y59076D01*
X410531Y62620D01*
X410649Y62579D01*
G03X413644Y61699I11003J31910D01*
G03X415937Y59641I11855J10902D01*
G01Y54210D01*
G03X418989Y26519I9563J-12960D01*
G01X419023Y26504D01*
X427325Y18202D01*
Y8000D01*
X506477D01*
Y23001D01*
G03X506740Y31422I-15403J4696D01*
G01X513019Y37701D01*
G03X522758Y47567I-5398J15069D01*
G01X525102Y49089D01*
X532156Y59945D01*
X535136D01*
G03X563324Y56098I15115J5555D01*
G01X576742D01*
G03X588550Y48329I13857J8203D01*
G01X588618Y48320D01*
X591940Y44998D01*
X591900Y44881D01*
G03X599424Y24926I15974J-5373D01*
G03X599884Y23001I15863J2773D01*
G01Y8000D01*
X775465D01*
Y172699D01*
X769544D01*
X763740Y178503D01*
Y193794D01*
X765153Y200450D01*
X800158Y365142D01*
X799450Y368473D01*
Y379370D01*
X803070Y382990D01*
X807643D01*
G03X812734Y383801I-3J16406D01*
G01X812851Y383839D01*
X820143Y376547D01*
Y373782D01*
X813394Y363389D01*
X807326Y334844D01*
Y295996D01*
G03X807330Y295664I15328J19D01*
G03X810266Y286197I17801J332D01*
G01Y262992D01*
G03X810491Y260277I16506J1D01*
G03X810411Y259193I16209J-1741D01*
G01X810403Y259004D01*
Y244000D01*
X811957D01*
Y193701D01*
G02X811024Y192768I-933J0D01*
G01X787402D01*
G03X780461Y185827I0J-6941D01*
G01Y3937D01*
G02X779528Y3004I-933J0D01*
G01X3937D01*
G02X3004Y3937I0J933D01*
G01Y1456693D01*
G02X3937Y1457626I933J0D01*
G01X7874D01*
G03X14815Y1464567I0J6941D01*
G01Y1515748D01*
G02X15748Y1516681I933J0D01*
G01X60039D01*
G02X60972Y1515748I0J-933D01*
G01Y1509055D01*
G03X67913Y1502114I6941J0D01*
G01X93504D01*
G03X100445Y1509055I0J6941D01*
G01Y1515748D01*
G02X101378Y1516681I933J0D01*
G01X280709D01*
G02X281642Y1515748I0J-933D01*
G01Y1500000D01*
G03X288583Y1493059I6941J0D01*
G01X493307D01*
G03X500248Y1500000I0J6941D01*
G01Y1515748D01*
G02X501181Y1516681I933J0D01*
G01X680512D01*
G02X681445Y1515748I0J-933D01*
G01Y1509055D01*
G03X688386Y1502114I6941J0D01*
G01X713976D01*
G03X720917Y1509055I0J6941D01*
G01Y1515748D01*
G02X721850Y1516681I933J0D01*
G01X775591D01*
G02X776524Y1515748I0J-933D01*
G01Y1500000D01*
G03X783465Y1493059I6941J0D01*
G01X988189D01*
G03X995130Y1500000I0J6941D01*
G01Y1515748D01*
G02X996063Y1516681I933J0D01*
G01X1059198D01*
G02X1059856Y1516408I-1J-933D01*
G01X1069361Y1506903D01*
G02X1069634Y1506245I-660J-660D01*
G01Y1421260D01*
G03X1076575Y1414319I6941J0D01*
G01X1085630D01*
G03X1092571Y1421260I0J6941D01*
G01Y1506245D01*
G02X1092844Y1506903I933J-1D01*
G01X1102349Y1516408D01*
G02X1103007Y1516681I659J-660D01*
G01X1207283D01*
G02X1208216Y1515748I0J-933D01*
G01Y1509055D01*
G03X1215157Y1502114I6941J0D01*
G01X1240748D01*
G03X1247689Y1509055I0J6941D01*
G01Y1515748D01*
G02X1248622Y1516681I933J0D01*
G01X1427953D01*
G02X1428886Y1515748I0J-933D01*
G01Y1500000D01*
G03X1435827Y1493059I6941J0D01*
G01X1640551D01*
G03X1647492Y1500000I0J6941D01*
G01Y1515748D01*
G02X1648425Y1516681I933J0D01*
G01X1827756D01*
G02X1828689Y1515748I0J-933D01*
G01Y1509055D01*
G03X1835630Y1502114I6941J0D01*
G01X1861220D01*
G03X1868161Y1509055I0J6941D01*
G01Y1515748D01*
G02X1869094Y1516681I933J0D01*
G01X1919094D01*
G02X1920027Y1515748I0J-933D01*
G01Y1464567D01*
G03X1926967Y1457626I6941J0D01*
G01X1930906D01*
G02X1931839Y1456693I0J-933D01*
G01Y3937D01*
G02X1930906Y3004I-933J0D01*
G01X1228346D01*
G02X1227413Y3937I0J933D01*
G01Y185827D01*
G03X1220472Y192768I-6941J0D01*
G01X1062992D01*
G02X1062059Y193701I0J933D01*
G01Y318738D01*
X1056763Y324034D01*
X1056757Y324042D01*
G03X1054356Y326443I-13450J-11049D01*
G01X1054348Y326449D01*
X1047929Y332868D01*
X1042884D01*
X1039805Y335947D01*
Y348611D01*
X1048774Y357580D01*
X1082389D01*
X1094189Y369380D01*
Y379198D01*
X1096957Y381966D01*
X1105477D01*
G03X1112779Y383681I-1J16406D01*
G03X1119877Y382066I7098J14791D01*
G01X1134656D01*
X1139286Y377436D01*
Y370078D01*
G03X1216843Y345722I42603J0D01*
G01X1216903Y345808D01*
X1218483D01*
X1220152Y344139D01*
X1231004Y210621D01*
Y191446D01*
G02X1232409Y185828I-10532J-5619D01*
G01Y8000D01*
X1428722D01*
Y23001D01*
G03X1429324Y29472I-15403J4696D01*
G01X1429313Y29567D01*
X1432140Y32394D01*
X1436000D01*
G03X1451708Y44942I0J16106D01*
G03X1466387Y63636I-1207J16058D01*
G01X1466384Y63652D01*
Y72456D01*
G03X1473080Y79656I-7883J14045D01*
G01X1475148D01*
X1476932Y77872D01*
X1485601Y64523D01*
Y57344D01*
X1485596Y57321D01*
Y57319D01*
G03X1501175Y37644I15579J-3670D01*
G01X1509400D01*
X1515014Y32030D01*
X1515029Y32001D01*
G03X1521668Y24926I15089J7507D01*
G03X1522128Y23001I15863J2773D01*
G01Y8000D01*
X1568224D01*
G03X1568366Y8341I0J200D01*
G01X1568244Y8463D01*
Y23001D01*
X1568246Y23003D01*
G03X1572667Y29582I-10746J11996D01*
G01X1572682Y29624D01*
X1577900Y34842D01*
G03X1591208Y53818I-2500J15908D01*
G01X1591204Y53837D01*
Y57679D01*
X1594332Y60807D01*
G03X1607777Y64583I-2206J33681D01*
G01X1607821Y64606D01*
X1608348D01*
X1610443Y62511D01*
Y59381D01*
X1610430Y59347D01*
G03X1625388Y37644I14958J-5697D01*
G01X1634072D01*
X1638835Y32881D01*
X1638850Y32846D01*
G03X1645881Y24926I15481J6662D01*
G03X1646341Y23001I15863J2773D01*
G01Y8000D01*
X1677147D01*
Y23001D01*
G03X1677821Y28605I-15403J4695D01*
G01X1681610Y32394D01*
X1684500D01*
G03X1698831Y41149I0J16107D01*
G01X1703113Y45431D01*
X1703165Y45445D01*
G03X1714810Y64057I-4165J15555D01*
G01X1714806Y64076D01*
Y67641D01*
X1715960Y68795D01*
X1718332D01*
X1733756Y58779D01*
Y55922D01*
X1733754Y55908D01*
G03X1749600Y37644I15846J-2258D01*
G01X1758399D01*
X1762964Y33079D01*
X1762979Y33042D01*
G03X1770093Y24926I15564J6466D01*
G03X1770553Y23001I15863J2773D01*
G01Y8000D01*
X1926843D01*
Y215957D01*
X1911842D01*
X1911831Y215958D01*
G03X1894522Y203745I-1662J-16017D01*
G03X1887475Y196969I8234J-15615D01*
G03X1867642Y176660I-4475J-15469D01*
G01X1867651Y176630D01*
Y171208D01*
X1867617Y171157D01*
G03X1883681Y146322I13382J-8957D01*
G01X1883783Y146339D01*
X1887063Y143059D01*
Y121317D01*
G03X1887525Y117487I16107J0D01*
G01X1887531Y117463D01*
Y114902D01*
G03X1882908Y106585I11138J-11634D01*
G01X1879429Y103106D01*
X1866740D01*
X1865963Y103883D01*
Y104642D01*
X1866334Y105013D01*
X1866375Y105028D01*
G03X1876834Y121800I-5558J15113D01*
G03X1863291Y148531I-12034J10699D01*
G01X1848925Y162897D01*
Y163697D01*
X1848940Y163733D01*
G03X1831257Y185645I-14921J6049D01*
G01X1831155Y185627D01*
X1823721Y193061D01*
X1823707Y193087D01*
G03X1809500Y201606I-14207J-7587D01*
G01X1805107D01*
X1802421Y204292D01*
Y207498D01*
X1803922Y208999D01*
X1803988Y209009D01*
G03X1840536Y251180I-6056J42171D01*
G01Y274780D01*
G03X1755330I-42603J0D01*
G01Y251180D01*
G03X1761621Y228899I42604J0D01*
G01Y193157D01*
G03X1763246Y179319I16922J-5027D01*
G01Y164868D01*
G03X1762850Y161319I15709J-3549D01*
G01Y154079D01*
X1759271Y150500D01*
X1755811D01*
X1755775Y150515D01*
G03X1733602Y136025I-6075J-14913D01*
G01X1733600Y135945D01*
X1731864Y134209D01*
X1727577D01*
X1720046Y135810D01*
X1702314Y153542D01*
X1702302Y153602D01*
G03X1695000Y164178I-15802J-3101D01*
G01Y172494D01*
G03X1698364Y175809I-9500J13005D01*
G01X1708023D01*
X1708051Y175801D01*
G03X1699627Y200906I4474J15467D01*
G01X1690199D01*
X1690170Y200915D01*
G03X1685503Y201606I-4667J-15415D01*
G01X1683770D01*
X1680358Y205018D01*
Y207369D01*
X1681366Y208377D01*
X1681433Y208386D01*
G03X1729036Y262991I-7516J54604D01*
G03X1620573Y249115I-55119J2D01*
G03X1649579Y213536I53344J13876D01*
G01X1649691Y213481D01*
Y210621D01*
X1649641Y210564D01*
G03X1646097Y203745I12104J-10621D01*
G03X1639793Y178117I8234J-15615D01*
G01X1639828Y178066D01*
Y174534D01*
X1637262Y171968D01*
X1633886D01*
X1586640Y202650D01*
Y229611D01*
G03X1592504Y251181I-36739J21570D01*
G01Y274781D01*
G03X1507319Y276105I-42603J0D01*
G01X1500961Y269747D01*
X1483319D01*
X1376704Y338984D01*
X1363324Y359588D01*
Y376839D01*
X1367479Y380994D01*
X1367561D01*
G03X1369324Y381097I-56J16105D01*
G01X1369335Y381098D01*
X1438503D01*
X1447638Y371963D01*
X1447652Y371934D01*
G03X1449835Y368666I14382J7244D01*
G03X1481506Y370182I15701J3578D01*
G01X1481515Y370250D01*
X1492260Y380995D01*
X1492341Y380997D01*
G03X1492014Y413206I-327J16103D01*
G01X1487004D01*
G03X1485488Y413134I5J-16106D01*
G03X1479138Y415523I-8718J-13539D01*
G03X1468544Y416449I-6621J-14679D01*
G03X1455374Y413102I-2989J-15823D01*
G01X1385228D01*
X1361218Y437113D01*
Y491449D01*
X1363670Y493901D01*
X1366972D01*
X1367026Y493858D01*
G03X1376963Y490400I9937J12549D01*
G01X1384695D01*
X1391384Y483711D01*
X1391397Y483689D01*
G03X1397456Y477682I14509J8575D01*
G03X1429377Y481658I15863J2771D01*
G01X1429370Y481749D01*
X1433015Y485394D01*
X1436000D01*
G03X1446154Y488998I0J16106D01*
G03X1465327Y507718I3346J15752D01*
G03X1466322Y516991I-14827J6281D01*
G01X1466319Y517010D01*
Y525419D01*
G03X1474606Y539500I-7819J14081D01*
G01Y545827D01*
X1477874Y549095D01*
X1480645D01*
X1490513Y533901D01*
X1491598Y528797D01*
Y519230D01*
G03X1501175Y490400I9577J-12824D01*
G01X1510029D01*
X1514501Y485928D01*
X1514516Y485891D01*
G03X1521668Y477682I15602J6373D01*
G03X1553617Y479711I15863J2771D01*
G01X1553621Y479789D01*
X1559226Y485394D01*
X1560500D01*
G03X1570654Y488998I0J16106D01*
G03X1589827Y507718I3346J15752D01*
G03X1590780Y517210I-14827J6282D01*
G01X1590776Y517230D01*
Y525396D01*
G03X1599064Y538332I-7775J14105D01*
G01X1599069Y538406D01*
X1602163Y541500D01*
X1604413D01*
X1615420Y524552D01*
X1615810Y522714D01*
Y519230D01*
G03X1625388Y490400I9578J-12824D01*
G01X1633353D01*
X1639508Y484245D01*
X1639522Y484220D01*
G03X1645881Y477682I14810J8043D01*
G03X1653248Y466773I15863J2771D01*
G01X1653268Y466761D01*
X1656000Y464029D01*
Y457063D01*
X1645358Y446421D01*
Y422493D01*
X1655145Y412706D01*
X1680573D01*
X1681573Y413706D01*
X1713573D01*
X1723909Y424042D01*
X1725877D01*
X1727000Y422919D01*
Y411071D01*
G03X1735014Y380994I8014J-13971D01*
G01X1740014D01*
G03X1750402Y384792I0J16106D01*
G01X1757091D01*
X1757108Y384789D01*
G03X1771985Y390000I2796J15858D01*
G01X1782277D01*
X1786000Y386277D01*
Y383360D01*
X1785994Y383336D01*
G03X1789441Y369022I15648J-3804D01*
G03X1819898Y366153I15701J3579D01*
G01X1836020Y382275D01*
G03X1835865Y413563I-3906J15625D01*
G01X1835810Y413576D01*
X1833590Y415796D01*
Y416865D01*
X1834431Y417706D01*
X1845021D01*
X1856201Y428886D01*
Y465077D01*
X1852482Y468795D01*
X1852474Y468865D01*
G03X1852143Y470756I-15999J-1826D01*
G01Y484144D01*
X1855628Y487629D01*
X1872345D01*
X1875116Y490400D01*
X1884319D01*
X1886362Y488357D01*
X1886375Y488302D01*
G03X1894306Y477682I16381J3962D01*
G03X1907380Y464593I15863J2771D01*
G03X1911841Y458242I15019J5808D01*
G01X1911910Y458182D01*
G03X1926842Y454921I10490J12218D01*
G01Y469075D01*
X1926843Y469076D01*
Y668713D01*
X1911842D01*
X1911831Y668714D01*
G03X1894522Y656501I-1662J-16017D01*
G03X1891038Y654089I8234J-15615D01*
G03X1871492Y634166I-4037J-15589D01*
G01X1871499Y634140D01*
Y628553D01*
G03X1884264Y599544I9001J-13352D01*
G01X1886805D01*
X1888188Y598161D01*
G03X1889215Y596032I14981J5914D01*
G01X1889242Y595985D01*
Y592165D01*
X1889215Y592118D01*
G03X1887063Y584075I13954J-8043D01*
G01Y574071D01*
G03X1887275Y571468I16107J2D01*
G01Y567408D01*
X1887217Y567349D01*
G03X1882792Y558730I11452J-11325D01*
G01X1882781Y558667D01*
X1880720Y556606D01*
X1880636D01*
G03X1880507I-65J-16106D01*
G01X1874334D01*
X1873209Y557731D01*
Y558715D01*
X1874469Y559975D01*
X1874482Y559984D01*
G03X1879686Y579606I-9482J13016D01*
G03X1860067Y600921I-14986J5893D01*
G01X1860038Y600913D01*
X1855024D01*
G03X1827229Y601343I-14023J-7914D01*
G02X1826489Y601598I-343J207D01*
G03X1820000Y616502I-15990J1903D01*
G01Y626287D01*
G03X1817566Y652441I-10500J12213D01*
G01X1817543Y652454D01*
X1815034Y654963D01*
Y663300D01*
X1818195Y666461D01*
X1818221Y666475D01*
G03X1840536Y703937I-20288J37462D01*
G01Y727537D01*
G03X1755330I-42603J0D01*
G01Y703937D01*
G03X1773415Y669097I42601J0D01*
G01X1773500Y669037D01*
Y662903D01*
G03X1770309Y656501I12457J-10205D01*
G03X1763589Y631505I8234J-15615D01*
G01Y618898D01*
G03X1762850Y614076I15366J-4823D01*
G01Y611332D01*
X1753252Y601734D01*
X1753218Y601719D01*
G03X1744615Y581500I6532J-14719D01*
G03X1757948Y559998I15135J-5500D01*
G01X1758018Y559990D01*
X1758690Y559318D01*
X1758669Y559213D01*
G03X1758507Y558265I15788J-3186D01*
G01X1758498Y558199D01*
X1757887Y557588D01*
X1719902Y565662D01*
X1719857Y565725D01*
G03X1716369Y569251I-13056J-9427D01*
G03X1703651Y582295I-15869J-2750D01*
G01X1703591Y582307D01*
X1700000Y585898D01*
Y594723D01*
G03X1697500Y615260I-13501J8777D01*
G01Y627757D01*
G03X1685500Y654606I-12000J10743D01*
G01X1681570D01*
X1676009Y660167D01*
G03X1646097Y656501I-14265J-7471D01*
G03X1639515Y631289I8234J-15615D01*
G01Y619318D01*
G03X1638711Y615608I15228J-5242D01*
G01X1638704Y615536D01*
X1635924Y612756D01*
X1627358D01*
X1576466Y645805D01*
X1576442Y645864D01*
G03X1568248Y654481I-14942J-6004D01*
G01X1565948Y656781D01*
Y664073D01*
X1566632Y664757D01*
X1566667Y664772D01*
G03X1592504Y703937I-16766J39165D01*
G01Y727537D01*
G03X1507298I-42603J0D01*
G01Y710981D01*
X1500704Y704387D01*
X1486259D01*
X1465359Y717959D01*
X1465183Y718788D01*
X1453320Y726493D01*
X1453319D01*
X1446275Y731068D01*
X1446274D01*
X1442761Y733349D01*
X1441931Y733173D01*
X1356455Y788682D01*
X1249597Y811392D01*
X1246093Y814896D01*
Y822850D01*
X1249437Y826194D01*
X1249506Y826202D01*
G03X1263008Y846827I-1918J15988D01*
G01X1263000Y846856D01*
Y853780D01*
X1270622Y861402D01*
X1310807Y865148D01*
X1325486Y850469D01*
Y843282D01*
G03X1325385Y822709I12338J-10347D01*
G03X1357278Y822816I15939J2291D01*
G01X1357287Y822883D01*
X1370501Y836097D01*
G03X1383007Y856270I-3002J15824D01*
G01X1383000Y856297D01*
Y867665D01*
X1389108Y873773D01*
X1559092Y894613D01*
X1559160Y894503D01*
G03X1588262Y898070I13740J8397D01*
G01X1588301Y898193D01*
X1680947Y909552D01*
X1693938Y896561D01*
X1693952Y896509D01*
G03X1725285Y903884I15548J4189D01*
G01X1725281Y903904D01*
Y909298D01*
X1731078Y915095D01*
X1734700Y915540D01*
X1735222Y916206D01*
X1770160Y920490D01*
X1776080D01*
X1776134Y920448D01*
G03X1779674Y918382I9821J12762D01*
G01X1779796Y918330D01*
Y917170D01*
X1778904Y916278D01*
X1778472D01*
X1778448Y916284D01*
G03X1774521Y916774I-3930J-15512D01*
G01X1766302D01*
X1766286Y916776D01*
G03X1761240I-2523J-16004D01*
G01X1761224Y916774D01*
X1760010D01*
G03X1748695Y912087I0J-16001D01*
G01X1735948Y899340D01*
G03X1733997Y896975I11312J-11319D01*
G01Y896974D01*
X1733986Y896958D01*
X1732559Y895531D01*
X1730557D01*
Y891534D01*
X1719762Y880739D01*
Y874920D01*
X1714324Y869482D01*
X1714239Y869483D01*
G03X1698592Y848637I-259J-16101D01*
G01X1698601Y848608D01*
Y842825D01*
G03X1698260Y821422I11860J-10893D01*
G03X1729594Y821135I15701J3578D01*
G01X1742678Y834219D01*
G03X1754035Y842199I-2677J15882D01*
G01X1759860Y848024D01*
X1787977D01*
X1791953Y852000D01*
X1809073D01*
X1812945Y848128D01*
X1822971D01*
G03X1823511Y846766I15224J5248D01*
G01X1823529Y846727D01*
Y843556D01*
X1823468Y843497D01*
G03X1822473Y821422I11206J-11565D01*
G03X1853641Y820519I15701J3579D01*
G01X1853655Y820568D01*
X1861408Y828321D01*
X1892590D01*
X1916293Y852024D01*
X1926843D01*
Y1126051D01*
G03X1911842Y1126622I-8042J-13951D01*
G03X1905238Y1120783I6957J-14523D01*
G03X1894522Y1109257I4931J-15329D01*
G03X1891252Y1107032I8233J-15615D01*
G03X1871829Y1086099I-4252J-15532D01*
G01X1871841Y1086066D01*
Y1081777D01*
G03X1883300Y1052343I8659J-13576D01*
G01X1883403Y1052361D01*
X1887374Y1048390D01*
Y1039981D01*
X1887370Y1039962D01*
G03X1887063Y1036833I15799J-3130D01*
G01Y1026828D01*
G03X1887357Y1023766I16107J1D01*
G01X1887361Y1023747D01*
Y1020250D01*
X1887302Y1020191D01*
G03X1882913Y1012122I11367J-11411D01*
G01X1882901Y1012064D01*
X1880079Y1009242D01*
X1871814D01*
G03X1871606Y1009240I51J-16106D01*
G01X1871521Y1009239D01*
X1871214Y1009546D01*
Y1010978D01*
X1871505Y1011269D01*
G03X1879577Y1032843I-6505J14731D01*
G03X1859436Y1053786I-15077J5657D01*
G01X1859405Y1053776D01*
X1855102D01*
G03X1830902Y1058544I-14102J-7776D01*
G01X1830847Y1058500D01*
X1826407D01*
G03X1819000Y1069677I-15908J-2499D01*
G01Y1077994D01*
G03X1822500Y1100508I-9500J13006D01*
G01Y1121886D01*
G03X1840536Y1156692I-24566J34806D01*
G01Y1180292D01*
G03X1755330I-42603J0D01*
G01Y1156692D01*
G03X1765041Y1129615I42605J0D01*
G01Y1105014D01*
G03X1765642Y1081592I13502J-11372D01*
G01X1765696Y1081534D01*
Y1075973D01*
G03X1762850Y1066831I13260J-9142D01*
G01Y1056829D01*
G03X1763718Y1051614I16106J1D01*
G01X1763729Y1051583D01*
Y1050268D01*
X1753306Y1039845D01*
G03X1747500Y1013943I5994J-14945D01*
G01Y1007177D01*
G03X1741422Y986660I8500J-13677D01*
G01X1741441Y986620D01*
Y979838D01*
G03X1739654Y976727I12898J-9478D01*
G01X1739620Y976648D01*
X1726349Y971890D01*
X1723283D01*
X1720974Y974199D01*
Y983992D01*
G03X1723106Y992000I-13973J8008D01*
G01Y1007000D01*
G03X1716578Y1019949I-16107J0D01*
G03X1700500Y1035106I-16078J-949D01*
G01X1690500D01*
G03X1687389Y1003197I0J-16106D01*
G01X1690894Y999692D01*
Y992000D01*
G03X1692282Y985461I16106J2D01*
G01X1692338Y985336D01*
X1691420Y984418D01*
X1689880D01*
X1688906Y985392D01*
Y987300D01*
G03X1668345Y1002778I-16106J0D01*
G01X1668318Y1002770D01*
X1667289D01*
X1666350Y1003709D01*
Y1008780D01*
G03X1665252Y1014625I-16106J0D01*
G03X1670850Y1026831I-10508J12206D01*
G01Y1028190D01*
X1682952Y1040292D01*
G03X1698000Y1067272I3548J15708D01*
G01Y1080844D01*
G03X1685500Y1107106I-12500J10156D01*
G01X1677763D01*
X1677743Y1107283D01*
G03X1646097Y1109257I-15999J-1830D01*
G03X1639399Y1084226I8234J-15615D01*
G01Y1071723D01*
G03X1638638Y1066831I15343J-4892D01*
G01Y1056831D01*
G03X1642119Y1046831I16106J1D01*
G03X1639188Y1041003I12625J-10000D01*
G03X1636302Y1040758I-86J-16103D01*
G03X1620500Y1017908I-1202J-16058D01*
G01Y1005761D01*
G03X1616330Y988595I11000J-11762D01*
G01X1616342Y988562D01*
Y980953D01*
X1612747Y977358D01*
X1600095Y973419D01*
X1598505D01*
X1596218Y975706D01*
Y982798D01*
G03X1599106Y992000I-13218J9202D01*
G01Y1007000D01*
G03X1592578Y1019949I-16107J0D01*
G03X1576500Y1035106I-16078J-949D01*
G01X1566500D01*
G03Y1002894I0J-16106D01*
G01X1566894D01*
Y991999D01*
G03X1568270Y985486I16105J1D01*
G01X1568287Y985448D01*
Y984674D01*
X1567518Y983905D01*
X1565717D01*
X1565658Y983993D01*
G03X1565048Y984839I-13360J-8990D01*
G01X1565006Y984893D01*
Y987600D01*
G03X1544944Y1003212I-16106J0D01*
G01X1544919Y1003206D01*
X1543341D01*
X1542137Y1004410D01*
Y1008780D01*
G03X1541039Y1014625I-16106J0D01*
G03X1546637Y1026831I-10508J12206D01*
G01Y1030531D01*
X1556979Y1040873D01*
X1557098Y1040830D01*
G03X1573000Y1068209I5401J15170D01*
G01Y1079724D01*
G03X1569000Y1105253I-11500J11276D01*
G01Y1118610D01*
G03X1592504Y1156692I-19099J38082D01*
G01Y1180292D01*
G03X1507298I-42603J0D01*
G01Y1156692D01*
G03X1515669Y1131331I42603J0D01*
G01Y1103784D01*
G03X1514984Y1084554I14449J-10142D01*
G01Y1071037D01*
G03X1514425Y1066831I15546J-4206D01*
G01Y1056831D01*
G03X1517906Y1046831I16106J1D01*
G03X1515001Y1041098I12625J-10000D01*
G03X1511810Y1040698I397J-16098D01*
G03X1496500Y1018493I-410J-16098D01*
G01Y1006003D01*
G03X1490722Y987913I9500J-13002D01*
G01Y987912D01*
X1490732Y987881D01*
Y980099D01*
X1487531Y976898D01*
X1479090Y974413D01*
X1476299D01*
X1474606Y976106D01*
Y1007000D01*
G03X1468078Y1019949I-16107J0D01*
G03X1452000Y1035106I-16078J-949D01*
G01X1442000D01*
G03X1437745Y1003466I0J-16106D01*
G01X1442394Y998817D01*
Y992000D01*
G03X1444506Y984027I16105J0D01*
G01X1444581Y983894D01*
X1443779Y983092D01*
X1441722D01*
X1441664Y983190D01*
G03X1440156Y985327I-13867J-8185D01*
G03X1440128Y985453I-15733J-3430D01*
G03X1427375Y1002766I-16028J1547D01*
G01X1427317Y1002778D01*
X1420187Y1009908D01*
Y1018641D01*
G03X1422425Y1026831I-13867J8190D01*
G01Y1036805D01*
X1427025Y1041405D01*
X1427104Y1041408D01*
G03X1430307Y1041853I-603J16092D01*
G03X1450500Y1066152I7693J14147D01*
G01Y1082216D01*
G03X1437000Y1107106I-13500J8784D01*
G01X1431448D01*
X1428851Y1109703D01*
G03X1397672Y1109257I-15532J-4250D01*
G03X1390827Y1084463I8234J-15615D01*
G01Y1071236D01*
G03X1390213Y1066832I15491J-4405D01*
G01Y1056831D01*
G03X1393694Y1046831I16106J1D01*
G03X1390736Y1040901I12625J-10000D01*
G03X1388172Y1040653I263J-16101D01*
G03X1374000Y1014961I-1272J-16053D01*
G01Y1005916D01*
G03X1368100Y987106I9200J-13216D01*
G01X1368101Y987105D01*
X1368113Y987071D01*
Y980612D01*
X1362325Y974824D01*
X1355982Y972445D01*
X1341466D01*
G03X1340520Y974422I-14965J-5946D01*
G01X1340494Y974468D01*
Y977051D01*
G03X1350606Y992000I-5994J14949D01*
G01Y1007000D01*
G03X1344078Y1019949I-16107J0D01*
G03X1328000Y1035106I-16078J-949D01*
G01X1318000D01*
G03X1314489Y1003281I0J-16106D01*
G01X1318394Y999376D01*
Y991998D01*
G03X1319404Y986384I16107J0D01*
G01X1319417Y986350D01*
Y984996D01*
X1318945Y984524D01*
X1317576D01*
X1316646Y985454D01*
X1316653Y985546D01*
G03X1299524Y1002866I-16053J1254D01*
G01X1299433Y1002860D01*
X1294490Y1007803D01*
Y1016533D01*
G03X1298212Y1026831I-12385J10298D01*
G01Y1035296D01*
X1304428Y1041512D01*
X1304497Y1041521D01*
G03X1306307Y1041853I-1995J15979D01*
G03X1326500Y1066152I7693J14147D01*
G01Y1082216D01*
G03X1325000Y1101743I-13500J8784D01*
G01Y1120915D01*
G03X1344473Y1156692I-23129J35777D01*
G01Y1180292D01*
G03X1259267I-42603J0D01*
G01Y1156692D01*
G03X1268207Y1130580I42604J0D01*
G01Y1105033D01*
G03X1266786Y1084187I13486J-11391D01*
G01Y1071801D01*
G03X1266000Y1066831I15320J-4970D01*
G01Y1056831D01*
G03X1268255Y1048613I16106J1D01*
G01X1268283Y1048566D01*
Y1045855D01*
X1266915Y1044487D01*
X1265244D01*
X1254526Y1055204D01*
X896702D01*
G03X885457Y1050587I0J-16002D01*
G03X901844Y1023200I10044J-12586D01*
G01X912008D01*
X921500Y1013708D01*
Y999117D01*
X921487Y999083D01*
G03X918814Y984231I39931J-14853D01*
G01Y962615D01*
X910645Y954446D01*
X900692D01*
X888772Y956021D01*
X888257Y956691D01*
X884099Y957242D01*
X884096Y957246D01*
X879925Y957796D01*
X879924Y957797D01*
X877094Y958170D01*
X875763Y958346D01*
X875762Y958347D01*
X874529Y958510D01*
X874251Y958547D01*
X874250D01*
X868824Y959262D01*
X863500Y964586D01*
Y968506D01*
X863512Y968540D01*
G03X854127Y989150I-15112J5560D01*
G03X839970Y997576I-14157J-7680D01*
G01X837653D01*
X837597Y997625D01*
G03X823720Y1001265I-10596J-12125D01*
G01X823700Y1001261D01*
X818552D01*
X802147Y984856D01*
X781064D01*
X773455Y992465D01*
Y1001218D01*
G03X767936Y1022359I-14206J7582D01*
G03X759535Y1043239I-14886J6141D01*
G01X759501Y1043254D01*
X748413Y1054342D01*
X748428Y1054442D01*
G03X748606Y1056825I-15928J2388D01*
G01Y1066831D01*
G03X747238Y1073326I-16106J-1D01*
G01Y1084582D01*
G03X749729Y1093016I-15151J9060D01*
G03X723853Y1109257I-10229J12437D01*
G03X720623Y1107066I8234J-15615D01*
G03X700802Y1087910I-4123J-15566D01*
G01X700807Y1087888D01*
Y1081207D01*
G03X711947Y1052182I9494J-13006D01*
G01X712041Y1052192D01*
X716712Y1047521D01*
Y1040016D01*
X716708Y1039996D01*
G03X716394Y1036831I15792J-3165D01*
G01Y1026831D01*
G03X717492Y1020986I16106J0D01*
G03X712505Y1013175I10508J-12206D01*
G01X708436Y1009106D01*
X701597D01*
X700879Y1009824D01*
Y1010979D01*
X701305Y1011405D01*
X701337Y1011420D01*
G03X709077Y1032843I-6837J14580D01*
G03X691014Y1054323I-15077J5656D01*
G01X690996Y1054320D01*
X684288D01*
G03X675737Y1030772I-13788J-8320D01*
G01X675769Y1030783D01*
X677036D01*
X678426Y1029393D01*
Y1028197D01*
X677335Y1027106D01*
X671000D01*
G03X660875Y998474I0J-16106D01*
G01Y987452D01*
G03X659633Y983773I14525J-6953D01*
G01X657413Y981553D01*
X650528D01*
X640537Y991544D01*
X640545Y991636D01*
G03X624280Y1009102I-16045J1364D01*
G01X622062Y1011320D01*
Y1016749D01*
X623259Y1017946D01*
X625587D01*
X625647Y1017878D01*
G03X641660Y1044121I12103J10622D01*
G01X629493Y1056288D01*
Y1097870D01*
G03X630179Y1111579I-14206J7583D01*
G01X630164Y1111615D01*
Y1113375D01*
X631045Y1114256D01*
X631118Y1114263D01*
G03X669866Y1156692I-3856J42429D01*
G01Y1180293D01*
G03X666415Y1197088I-42603J-2D01*
G01Y1197089D01*
X666399Y1197127D01*
Y1201662D01*
X667405Y1202668D01*
X669309D01*
X710779Y1161198D01*
X737121D01*
X744491Y1153828D01*
Y1143924D01*
X744480Y1143859D01*
G03X743731Y1136524I15220J-5260D01*
G03X774893Y1129490I16031J-1523D01*
G01X774908Y1129532D01*
X780415Y1135039D01*
X790268D01*
X790297Y1135030D01*
G03X797428Y1134466I4803J15370D01*
G03X803818Y1135160I1491J16034D01*
G01X822454D01*
G03X843146I10346J12340D01*
G01X908836D01*
X935905Y1162229D01*
X946504D01*
X946536Y1162218D01*
G03X956910I5187J15351D01*
G01X956942Y1162229D01*
X963426D01*
X965500Y1160155D01*
Y1157033D01*
X965499Y1157032D01*
Y1155648D01*
X962352Y1152501D01*
X935286D01*
X930341Y1147556D01*
X926744D01*
Y1143959D01*
X924499Y1141714D01*
Y1119214D01*
X921549Y1116264D01*
Y1096836D01*
X912115Y1087402D01*
X847057D01*
G03Y1056398I-4357J-15502D01*
G01X1004631D01*
X1019701Y1071467D01*
G03X1022295Y1074909I-10963J10961D01*
G01X1022308Y1074933D01*
X1023597Y1076222D01*
X1024795D01*
Y1078089D01*
X1024851Y1078147D01*
G03X1025095Y1078407I-11622J11151D01*
G01X1025155Y1078472D01*
X1025474D01*
G03X1036353Y1082930I0J15503D01*
G01X1041790D01*
Y1086881D01*
G03X1046255Y1092948I-10791J12618D01*
G03X1049728Y1102725I-12029J9778D01*
G01Y1106875D01*
G03X1048435Y1113072I-15503J-1D01*
G03X1045025Y1123986I-16074J967D01*
G03X1044493Y1126790I-16025J-1588D01*
G03X1043501Y1143210I-14315J7375D01*
G01Y1156214D01*
X1028714Y1171001D01*
X1006286D01*
X998606Y1178681D01*
Y1226763D01*
X1004865Y1233022D01*
X1089576D01*
X1092994Y1229604D01*
Y1221715D01*
X1091733Y1220454D01*
X1085917D01*
G03X1057036Y1207267I-13317J-9053D01*
G03X1056906Y1202633I15864J-2764D01*
G03X1070574Y1175552I11663J-11103D01*
G03X1077334Y1175992I2357J15930D01*
G01X1077361Y1176000D01*
X1080867D01*
X1083000Y1173867D01*
Y1166289D01*
X1082997Y1166271D01*
G03X1084577Y1153219I21531J-4015D01*
G01Y1137086D01*
G03X1085179Y1126339I16828J-4448D01*
G03X1101405Y1102634I16226J-6299D01*
G01X1108099D01*
G03X1113865Y1103617I-1J17406D01*
G03X1119630Y1102634I5767J16423D01*
G01X1126326D01*
G03X1142552Y1126339I0J17406D01*
G03X1131797Y1149162I-16226J6299D01*
G01X1126895Y1154064D01*
Y1157442D01*
X1132347Y1162894D01*
X1155900D01*
G03X1172306Y1179300I0J16406D01*
G01Y1188900D01*
G03X1155900Y1205306I-16406J0D01*
G01X1155602D01*
X1149706Y1211202D01*
Y1227384D01*
X1155344Y1233022D01*
X1244562D01*
X1282416Y1270877D01*
Y1380860D01*
X1291900Y1390344D01*
X1647201D01*
X1669965Y1413108D01*
X1670043Y1413111D01*
G03X1678631Y1416022I-666J16089D01*
G03X1682225Y1416902I-2007J15977D01*
G03X1689331Y1416699I4001J15598D01*
G01X1689350Y1416703D01*
X1690692D01*
X1703656Y1403739D01*
X1703651Y1403649D01*
G03X1734860Y1397198I16075J-948D01*
G01X1738144Y1400482D01*
G03X1744238Y1403023I-3019J15818D01*
G01X1760209D01*
G03X1780266Y1420440I3717J15977D01*
G03X1782557Y1425925I-13740J8960D01*
G01X1787632Y1431000D01*
X1789719D01*
X1789748Y1430991D01*
G03X1795775Y1430354I4676J15409D01*
G03X1816128Y1442703I4551J15446D01*
G03X1819231Y1449516I-12702J9898D01*
G01X1824515Y1454800D01*
X1824600Y1454799D01*
G03X1839841Y1465081I226J16101D01*
G01X1840973Y1466213D01*
X1848327D01*
X1850381Y1464159D01*
X1850368Y1464061D01*
G03X1877482Y1443925I19132J-2561D01*
G03X1885521Y1450733I-7982J17575D01*
G01X1889693Y1454905D01*
G03X1900030Y1487272I4507J16395D01*
G03X1881334Y1482416I-5830J-15972D01*
G01X1876972D01*
X1875859Y1483529D01*
X1875867Y1483622D01*
G03X1868390Y1499511I-17442J1496D01*
G02X1861221Y1497118I-7170J9544D01*
G01X1835630D01*
G02X1823693Y1509055I0J11937D01*
G01Y1511685D01*
X1652488D01*
Y1500000D01*
G02X1645877Y1489317I-11937J0D01*
G01Y1486404D01*
G03X1645000Y1476448I15749J-6404D01*
G01Y1472769D01*
G03X1640500Y1457906I11250J-11519D01*
G01Y1441501D01*
X1636901Y1437902D01*
X1406024D01*
X1401016Y1442910D01*
X1401027Y1443006D01*
G03X1400019Y1451928I-19925J2267D01*
G01X1400008Y1451960D01*
Y1460245D01*
X1400019Y1460277D01*
G03X1399511Y1474878I-18917J6651D01*
G01X1399495Y1474916D01*
Y1485633D01*
X1399519Y1485677D01*
G03X1402030Y1496674I-18418J9991D01*
G01Y1511685D01*
X1252685D01*
Y1509055D01*
G02X1240748Y1497118I-11937J0D01*
G01X1215157D01*
G02X1207987Y1499511I0J11937D01*
G03X1200497Y1486456I9966J-14394D01*
G01X1200498Y1486455D01*
X1200491Y1486364D01*
G03X1217953Y1467612I17462J-1246D01*
G01X1225564D01*
X1231772Y1461404D01*
Y1438895D01*
X1225870Y1432993D01*
X1213750D01*
G03X1198628Y1428956I-3931J-15616D01*
G03X1194270Y1427670I2333J-15933D01*
G01X1097567D01*
Y1421260D01*
G02X1085630Y1409323I-11937J0D01*
G01X1076575D01*
G02X1064638Y1421260I0J11937D01*
G01Y1504561D01*
X1057514Y1511685D01*
X1000126D01*
Y1500000D01*
G02X988189Y1488063I-11937J0D01*
G01X783465D01*
G02X771528Y1500000I0J11937D01*
G01Y1511685D01*
X725913D01*
Y1509055D01*
G02X716562Y1497402I-11937J0D01*
G01X685800D01*
G02X676449Y1509055I2586J11653D01*
G01Y1511685D01*
X505244D01*
Y1500000D01*
G02X493307Y1488063I-11937J0D01*
G01X357340D01*
X323480Y1454202D01*
X253895D01*
X251762Y1456335D01*
Y1457897D01*
X251783Y1457939D01*
G03X252587Y1474093I-17925J8989D01*
G01X252574Y1474128D01*
Y1486250D01*
G03X254786Y1496684I-18716J9419D01*
G03X250287Y1508674I-20928J-1014D01*
G01X250244Y1508728D01*
Y1511685D01*
X105441D01*
Y1509055D01*
G02X93504Y1497118I-11937J0D01*
G01X67913D01*
G02X55976Y1509055I0J11937D01*
G01Y1511685D01*
X19811D01*
Y1465877D01*
X23780Y1461908D01*
G03X31741Y1449886I16820J2492D01*
G01X31875Y1449806D01*
G03X43290Y1447611I8725J14594D01*
G01X43306Y1447614D01*
X45341D01*
G03X81099Y1446856I18033J6886D01*
G01X83743Y1449500D01*
X90041D01*
G03X97240Y1442671I14143J7700D01*
G03X105392Y1427680I16074J-971D01*
G03X104994Y1424192I15104J-3490D01*
G01Y1410262D01*
G03Y1400836I15502J-4713D01*
G01Y1296582D01*
X190578Y1210998D01*
X324134D01*
X336629Y1198503D01*
Y1162777D01*
X328555Y1154703D01*
Y1100206D01*
X322048Y1093699D01*
Y1072733D01*
G03X342120Y1052774I15452J-4533D01*
G01X342148Y1052782D01*
X344274D01*
G03X347237Y1046831I15589J4048D01*
G03X343756Y1036831I12625J-10001D01*
G01Y1026831D01*
G03X344854Y1020986I16106J0D01*
G03X339270Y1009433I10509J-12205D01*
G02X338837Y1009051I-400J17D01*
G03X337510Y1009106I-1330J-16051D01*
G01X329155D01*
X328533Y1009728D01*
Y1010936D01*
X329185Y1011588D01*
X329214Y1011602D01*
G03X336405Y1033198I-7214J14397D01*
G03X313220Y1052487I-15205J5302D01*
G02X312657Y1052669I-199J347D01*
G03X304768Y1031388I-14657J-6669D01*
G01X306002Y1030154D01*
Y1028146D01*
X304962Y1027106D01*
X298500D01*
G03X292250Y996156I0J-16106D01*
G01Y990939D01*
G03X286100Y980020I9850J-12739D01*
G01X284639Y978559D01*
X279129D01*
X272581Y979557D01*
X272532Y979631D01*
G03X268292Y983951I-13337J-8850D01*
G01X268206Y984010D01*
Y985831D01*
G03X267802Y989403I-16006J-1D01*
G03X261089Y1005792I-15802J3097D01*
G01Y1008798D01*
X264692Y1012401D01*
X264771Y1012404D01*
G03X279527Y1033593I-520J16095D01*
G03X259310Y1054510I-15077J5656D01*
G01X259279Y1054500D01*
X252041D01*
G02X251644Y1054947I0J400D01*
G03X251755Y1056831I-15995J1888D01*
G01Y1066831D01*
G03X248136Y1077003I-16106J0D01*
G01X248091Y1077058D01*
Y1081542D01*
X248145Y1081600D01*
G03X252878Y1093016I-12909J12041D01*
G03X227002Y1109257I-10229J12437D01*
G03X223853Y1107135I8233J-15615D01*
G03X206276Y1083077I-3853J-15635D01*
G02X206119Y1082512I-341J-210D01*
G03X218256Y1052815I7381J-14312D01*
G01X218285Y1052824D01*
X219653D01*
X220200Y1052277D01*
X220214Y1052229D01*
G03X221257Y1049602I15433J4607D01*
G01X221278Y1049559D01*
Y1044102D01*
X221257Y1044059D01*
G03X219543Y1036831I14392J-7230D01*
G01Y1026831D01*
G03X220641Y1020986I16106J0D01*
G03X215364Y1011980I10508J-12206D01*
G01X212490Y1009106D01*
X205354D01*
X204497Y1009963D01*
Y1010967D01*
X205054Y1011524D01*
X205084Y1011539D01*
G03X212463Y1033080I-7084J14461D01*
G03X193894Y1054239I-15163J5420D01*
G01X193873Y1054234D01*
X187839D01*
G03X179881Y1031009I-13839J-8234D01*
G01X181416D01*
X181758Y1030667D01*
Y1027589D01*
X181275Y1027106D01*
X174500D01*
G03X163219Y999504I0J-16106D01*
G01Y983606D01*
G03X162300Y980249I14981J-5905D01*
G01X159584Y977533D01*
X151918D01*
X149144Y978242D01*
X149102Y978320D01*
G03X144080Y983951I-14120J-7538D01*
G01X143994Y984010D01*
Y985832D01*
G03X141487Y994432I-16006J-1D01*
G03X135733Y1004933I-15986J-1933D01*
G01Y1008370D01*
X139789Y1012426D01*
X139878Y1012421D01*
G03X155929Y1033875I872J16079D01*
G03X139754Y1055322I-15179J5375D01*
G01X139664Y1055316D01*
X127531Y1067449D01*
X127528Y1067527D01*
G03X125076Y1075397I-16091J-696D01*
G01X125045Y1075446D01*
Y1082916D01*
G03X128666Y1093016I-14021J10726D01*
G03X133564Y1110973I-10229J12437D01*
G01X133552Y1111006D01*
Y1113033D01*
X134757Y1114238D01*
X134830Y1114244D01*
G03X173803Y1156692I-3630J42448D01*
G01Y1180292D01*
G03X88597I-42603J0D01*
G01Y1106587D01*
G02X88457Y1105981I-315J-246D01*
G03X81776Y1083077I7043J-14481D01*
G02X81619Y1082512I-341J-210D01*
G03X89918Y1052123I7381J-14312D01*
G01X90008Y1052128D01*
X97402Y1044734D01*
X97330Y1044602D01*
G03X95331Y1036831I14107J-7771D01*
G01Y1026831D01*
G03X96429Y1020986I16106J0D01*
G03X90844Y1009426I10508J-12206D01*
G02X90410Y1009044I-399J16D01*
G03X89000Y1009106I-1412J-16044D01*
G01X79522D01*
G03X79017Y1010422I-15272J-5106D01*
G02X79242Y1010955I367J159D01*
G03X87866Y1033275I-5742J15045D01*
G03X64733Y1052450I-15266J5125D01*
G02X64173Y1052635I-195J349D01*
G03X41000Y1032324I-14673J-6634D01*
G01Y1024357D01*
G03X48267Y994987I9000J-13357D01*
G03X49276Y987068I15983J-1987D01*
G02X49009Y986535I-372J-147D01*
G03X62687Y957952I4241J-15535D01*
G01X82913D01*
G03X91709Y952347I12587J10048D01*
G01X94730Y949326D01*
G03X95696Y938014I16294J-4306D01*
G01X95714Y937975D01*
Y934779D01*
X93414Y932479D01*
X93397Y932467D01*
G03X87513Y925486I8866J-13443D01*
G03X85438Y924860I3603J-15694D01*
G03X80914Y924825I-2139J-15960D01*
G01X80899Y924823D01*
X72449D01*
X70107Y922481D01*
X65657D01*
Y918031D01*
X63814Y916188D01*
X63702Y916218D01*
G03X59521Y916774I-4182J-15447D01*
G01X51302D01*
X51286Y916776D01*
G03X46240I-2523J-16004D01*
G01X46224Y916774D01*
X45010D01*
G03X33695Y912087I0J-16001D01*
G01X23001Y901394D01*
X8000D01*
Y847024D01*
X24681D01*
X28458Y843247D01*
Y838970D01*
X28438Y838929D01*
G03X30741Y821422I14504J-6997D01*
G03X62376Y827330I15701J3577D01*
G01X62361Y827429D01*
X68926Y833994D01*
X73526D01*
G03X88996Y845619I0J16106D01*
G01X91487Y848110D01*
X121916D01*
X125830Y852024D01*
X134600D01*
X136762Y849862D01*
Y837762D01*
X153852Y820672D01*
X153865Y820620D01*
G03X183199Y816330I15577J4080D01*
G03X192514Y828831I-6641J14670D01*
G01X192523Y828898D01*
X197706Y834081D01*
X197776Y834089D01*
G03X210096Y857938I-1750J16011D01*
G01X210023Y858070D01*
X218264Y866311D01*
Y899739D01*
X212820Y905183D01*
X212806Y905234D01*
G03X212776Y905341I-15519J-4294D01*
G01X212769Y905368D01*
Y914281D01*
X210722D01*
X209519Y915484D01*
Y920581D01*
X204422D01*
X200477Y924526D01*
X189818D01*
X186000Y928344D01*
Y933839D01*
X195047D01*
X228649Y925252D01*
X228691Y925179D01*
G03X251043Y919467I13958J8030D01*
G01X251115Y919511D01*
X315098Y903159D01*
X542181Y871359D01*
X550000Y863540D01*
Y858018D01*
X549974Y857973D01*
G03X558829Y834855I14051J-7873D01*
G01X563156Y830528D01*
X563164Y830460D01*
G03X566873Y821988I15984J1950D01*
G03X597867Y830485I15775J3235D01*
G01X597856Y830517D01*
Y834479D01*
X601954Y838577D01*
G03X610157Y852768I-7899J14032D01*
G01X610156Y852852D01*
X618040Y860736D01*
X639724Y857699D01*
X643576Y853847D01*
X643572Y853759D01*
G03X644615Y847344I16089J-676D01*
G01X644628Y847310D01*
Y842890D01*
X644572Y842832D01*
G03X643941Y821122I11570J-11200D01*
G03X675743Y824469I15700J3579D01*
G01X675744Y824550D01*
X685188Y833994D01*
X685526D01*
G03X695051Y837112I0J16108D01*
G01X701844D01*
X704641Y834315D01*
Y803149D01*
G03X719928Y770456I42602J0D01*
G01X720000Y770396D01*
Y765087D01*
X714611Y759698D01*
G03X702286Y741538I3589J-15698D01*
G03X711529Y723799I15814J-3038D01*
G01X714062Y721266D01*
Y718128D01*
X682607Y697708D01*
X674941D01*
X669866Y702783D01*
Y727537D01*
G03X584660I-42603J0D01*
G01Y703937D01*
G03X594271Y676983I42602J0D01*
G01X594316Y676928D01*
Y666336D01*
X564776Y636796D01*
X538874Y631291D01*
X532090Y638075D01*
X532086Y638153D01*
G03X510342Y652489I-16086J-740D01*
G01X510308Y652476D01*
X510059D01*
X508093Y654442D01*
Y658632D01*
X510577Y661116D01*
X510644Y661125D01*
G03X520587Y663425I-7397J54622D01*
G03X558367Y715745I-17340J52322D01*
G01Y715748D01*
G03X503248Y770868I-55120J0D01*
G01X503247D01*
G03X464548Y676496I0J-55121D01*
G01Y655852D01*
X462228Y653532D01*
X462189Y653517D01*
G03X452823Y633122I5812J-15017D01*
G01X452834Y633090D01*
Y623188D01*
X439900Y610254D01*
X429164Y607972D01*
X429101Y608004D01*
G03X409326Y603800I-7281J-14363D01*
G01X409281Y603745D01*
X399945Y601761D01*
X399874Y601811D01*
G03X385205Y603785I-9242J-13187D01*
G01X380116Y608874D01*
Y641108D01*
X387164Y648156D01*
Y662079D01*
G03X421835Y703937I-7932J41858D01*
G01Y727537D01*
G03X336629I-42603J0D01*
G01Y703937D01*
G03X340953Y685236I42602J0D01*
G01Y656161D01*
X338385Y653593D01*
G03X328461Y634276I5615J-15092D01*
G01X328468Y634250D01*
Y628532D01*
G03X321399Y615482I9032J-13332D01*
G01X321398Y615401D01*
X314017Y608020D01*
X303805D01*
X303770Y608033D01*
G03X284025Y601000I-5770J-15033D01*
G01X271211D01*
G03X258326Y601017I-6462J-14750D01*
G01X258288Y601000D01*
X255623D01*
X251755Y604868D01*
Y614075D01*
G03X249972Y621440I-16106J-1D01*
G01Y631166D01*
G03X252878Y640260I-14736J9720D01*
G03X227002Y656501I-10229J12437D01*
G03X223522Y654093I8232J-15616D01*
G03X203913Y634460I-4021J-15593D01*
G01Y634458D01*
X203919Y634433D01*
Y628142D01*
G03X217446Y599588I9582J-12942D01*
G01X220181D01*
G03X221847Y595773I15469J4484D01*
G01X221876Y595726D01*
Y592424D01*
X221847Y592377D01*
G03X219543Y584077I13802J-8301D01*
G01Y574075D01*
G03X220641Y568230I16106J0D01*
G03X215157Y557939I10508J-12206D01*
G01X215149Y557870D01*
X213381Y556102D01*
X213296Y556104D01*
G03X213002Y556106I-257J-16104D01*
G01X210121D01*
X208879Y557348D01*
Y559998D01*
X209563Y560682D01*
Y562331D01*
X209613Y562388D01*
G03X212186Y579606I-12113J10611D01*
G03X191674Y600625I-14986J5894D01*
G01X191641Y600613D01*
X187690D01*
G03X160371Y602324I-14190J-7613D01*
G01X147948D01*
G03X140094Y602839I-4949J-15324D01*
G01X139991Y602820D01*
X127543Y615268D01*
Y631593D01*
X173803Y677853D01*
Y727537D01*
G03X88597I-42603J0D01*
G01Y655114D01*
X78656Y645173D01*
Y627542D01*
G03X93275Y599675I10344J-12342D01*
G01X93301Y599682D01*
X95942D01*
G03X97056Y596825I15494J4396D01*
G01X97077Y596782D01*
Y591368D01*
X97056Y591325D01*
G03X95331Y584075I14381J-7252D01*
G01Y574075D01*
G03X96429Y568230I16106J0D01*
G03X90940Y557896I10508J-12206D01*
G01X90932Y557827D01*
X89211Y556106D01*
X89127D01*
G03X89007I-60J-16106D01*
G01X80618D01*
X80147Y556577D01*
Y558159D01*
X80474Y558486D01*
X80504Y558501D01*
G03X87963Y580080I-7004J14500D01*
G03X67895Y600838I-15163J5420D01*
G01X67865Y600828D01*
X63573D01*
G03X34443Y587292I-14073J-7828D01*
G01Y562170D01*
G03X40557Y544952I15557J-4170D01*
G01Y527909D01*
G03X62904Y505111I12693J-9910D01*
G01X82724D01*
G03X90958Y500950I11075J11689D01*
G01X91020Y500939D01*
X94875Y497084D01*
G03X102574Y477682I16149J-4820D01*
G03X105899Y470348I15863J2771D01*
G01Y420686D01*
X117022Y409563D01*
X141541D01*
X142266Y410288D01*
X170804D01*
X173793Y413277D01*
X175361D01*
X176344Y412294D01*
Y400182D01*
X176216Y400054D01*
Y388261D01*
G03X177141Y368422I13126J-9329D01*
G03X208940Y371605I15701J3579D01*
G01X208942Y371685D01*
X218760Y381503D01*
X218838Y381506D01*
G03X231999Y389269I-623J16094D01*
G01X235693Y392963D01*
X272145D01*
X275447Y389661D01*
Y383246D01*
X275441Y383222D01*
G03X278841Y368722I15601J-3990D01*
G03X310501Y370151I15701J3579D01*
G01X310510Y370218D01*
X321841Y381549D01*
X321913Y381555D01*
G03X323462Y413434I-1399J16045D01*
G01X316091Y420805D01*
Y462001D01*
X310647Y467447D01*
X310633Y467499D01*
G03X310596Y467633I-15540J-4219D01*
G01Y481951D01*
X305757Y486790D01*
X285977D01*
X283491Y489276D01*
Y495115D01*
X281005Y497601D01*
Y504910D01*
X285184Y507624D01*
X289435D01*
G03X314029Y507581I12315J10376D01*
G01X328597D01*
G03X338405Y501059I13203J9219D01*
G01X343102Y496362D01*
G03X350999Y477682I16347J-4098D01*
G03X382644Y483651I15863J2770D01*
G01X389878Y490885D01*
G03X397428Y497804I-6471J14640D01*
G01X397472Y497884D01*
X412942Y501168D01*
X418279D01*
G03X441670Y502792I10931J11824D01*
G01X458238D01*
G03X463863Y500940I7762J14108D01*
G01X463930Y500931D01*
X467574Y497287D01*
G03X475211Y477682I16087J-5023D01*
G03X506869Y483584I15863J2771D01*
G01X514235Y490950D01*
G03X522959Y500951I-6615J14575D01*
G01X522975Y501006D01*
X530975Y508094D01*
X537555D01*
G03X555512Y502781I12695J9906D01*
G01X555544Y502792D01*
X563653D01*
X569252Y497193D01*
X569266Y497166D01*
G03X586900Y488850I14284J7434D01*
G01X586921Y488854D01*
X588536D01*
X592943Y484447D01*
G03X599424Y477682I14931J7817D01*
G03X630974Y484088I15862J2772D01*
G01X630949Y484196D01*
X637198Y490445D01*
X637240Y490460D01*
G03X645869Y497832I-5407J15065D01*
G01X659245D01*
G03X676457Y502049I5406J15168D01*
G03X680196Y503035I-2207J15951D01*
G01X680231Y503049D01*
X684654D01*
G03X697281Y495051I13946J8051D01*
G01X697354Y495045D01*
X699290Y493109D01*
X699305Y493064D01*
G03X701201Y489167I15297J5033D01*
G01X701235Y489117D01*
Y483821D01*
G37*
G36*
G01X37788Y879500D02*
X37263Y880025D01*
Y887025D01*
X47263Y897025D01*
X59263D01*
X59763Y896525D01*
Y891025D01*
X61763Y889024D01*
Y884525D01*
X63763Y882525D01*
Y880025D01*
X63464Y879726D01*
X60765D01*
X60564Y879525D01*
X60263D01*
X60238Y879500D01*
X37788D01*
G37*
G36*
G01X81462Y902424D02*
X84864D01*
X85103Y902522D01*
X86683Y900942D01*
X86697Y900891D01*
G03X87816Y899772I1544J425D01*
G01X87867Y899758D01*
X91242Y896384D01*
Y893542D01*
X91400D01*
Y887302D01*
X91241D01*
Y886202D01*
X91062Y886023D01*
Y874527D01*
X91241Y874348D01*
Y873917D01*
X90685Y873361D01*
X79104D01*
X78951Y873514D01*
X78964Y873527D01*
Y887226D01*
X78759D01*
Y889271D01*
X78758D01*
Y891238D01*
X78400D01*
Y893542D01*
X78758D01*
Y896475D01*
G03X79465Y898897I-1495J1751D01*
G01X79456Y898926D01*
Y900918D01*
X81120Y902582D01*
G02X81462Y902441I142J-141D01*
G01Y902424D01*
G37*
G36*
G01X90228Y907666D02*
Y905064D01*
X89623Y904459D01*
X84864D01*
Y905026D01*
X81462D01*
Y904459D01*
X79763D01*
X78397Y905825D01*
X78363D01*
Y909522D01*
X78663Y909822D01*
X87263D01*
Y909825D01*
X88805D01*
X88817Y909638D01*
G03X90228Y907666I2297J153D01*
G37*
G36*
G01X33763Y862025D02*
X20763D01*
X19763Y863025D01*
Y874525D01*
X20763Y875525D01*
X33763D01*
X34763Y874525D01*
Y863025D01*
X33763Y862025D01*
G37*
G36*
G01X104177Y863111D02*
X92752Y874536D01*
Y886014D01*
X92905Y886168D01*
X93545D01*
X93599Y886125D01*
G03X94643Y885768I1043J1344D01*
G01X96426D01*
X97695Y884498D01*
X103029D01*
X104730Y886200D01*
X114913D01*
X116763Y884350D01*
Y864172D01*
X115702Y863111D01*
X104177D01*
G37*
G36*
G01X59763Y877025D02*
X61183Y878445D01*
X61279Y878434D01*
G03X61463Y878424I179J1591D01*
G01X63063D01*
G03X63593Y878514I1J1601D01*
G01X63625Y878525D01*
X64263D01*
X65263Y879525D01*
Y883525D01*
X66263Y884525D01*
X68763D01*
X69639Y885401D01*
X69761Y885353D01*
G03X72003Y885668I842J2142D01*
G01X77248D01*
Y873510D01*
X66763Y863025D01*
X38263D01*
X36763Y864525D01*
Y876025D01*
X37763Y877025D01*
X59763D01*
G37*
G36*
G01X135879Y441500D02*
X135090Y442289D01*
Y443324D01*
G03X135092Y443389I-1599J82D01*
G01Y445989D01*
G03X135090Y446054I-1601J-17D01*
G01Y449289D01*
X145090Y459289D01*
X157090D01*
X157590Y458789D01*
Y453289D01*
X159590Y451288D01*
Y446789D01*
X161590Y444789D01*
Y442289D01*
X161291Y441990D01*
X158592D01*
X158391Y441789D01*
X158090D01*
X157801Y441500D01*
X135879D01*
G37*
G36*
G01X185694Y462022D02*
X189227Y458489D01*
Y449566D01*
X189068D01*
Y448466D01*
X188888Y448287D01*
Y436791D01*
X189068Y436612D01*
Y436181D01*
X188512Y435625D01*
X176931D01*
X176778Y435778D01*
X176792Y435791D01*
Y449490D01*
X176586D01*
Y453503D01*
X176227D01*
Y455806D01*
X176586D01*
Y458739D01*
G03X177292Y461161I-1496J1750D01*
G01X177283Y461190D01*
Y463182D01*
X178947Y464846D01*
G02X179288Y464705I141J-141D01*
G01Y464688D01*
X182692D01*
X182930Y464786D01*
X184510Y463206D01*
X184524Y463155D01*
G03X185643Y462036I1544J425D01*
G01X185694Y462022D01*
G37*
G36*
G01X177590Y466723D02*
X176224Y468089D01*
X176190D01*
Y471786D01*
X176490Y472086D01*
X185090D01*
Y472089D01*
X186632D01*
X186644Y471902D01*
G03X188055Y469930I2297J153D01*
G01Y467328D01*
X187450Y466723D01*
X182692D01*
Y467290D01*
X179288D01*
Y466723D01*
X177590D01*
G37*
G36*
G01X135327Y424564D02*
X123236D01*
X120900Y426900D01*
Y438100D01*
X123864Y441064D01*
X133527D01*
X134000Y440591D01*
Y433500D01*
X136227Y431273D01*
Y425464D01*
X135327Y424564D01*
G37*
G36*
G01X202871Y424508D02*
X190578Y436801D01*
Y448278D01*
X190733Y448432D01*
X191372D01*
X191426Y448389D01*
G03X192470Y448032I1043J1344D01*
G01X194553D01*
X195722Y446862D01*
X200825D01*
X202426Y448464D01*
X212740D01*
X214590Y446614D01*
Y430789D01*
X214554Y430753D01*
Y426366D01*
X212696Y424508D01*
X202871D01*
G37*
G36*
G01X166590Y446789D02*
X167466Y447665D01*
X167588Y447617D01*
G03X169830Y447932I842J2142D01*
G01X175076D01*
Y435775D01*
X164590Y425289D01*
X138627D01*
X137428Y426488D01*
Y431771D01*
X137427Y431772D01*
Y432573D01*
X135296Y434704D01*
Y438296D01*
X136000Y439000D01*
X157301D01*
X159010Y440709D01*
X159106Y440698D01*
G03X159290Y440688I179J1591D01*
G01X160890D01*
G03X161420Y440778I1J1601D01*
G01X161452Y440789D01*
X162090D01*
X163090Y441789D01*
Y445789D01*
X164090Y446789D01*
X166590D01*
G37*
G36*
G01X127653Y553877D02*
Y561803D01*
X128679Y562829D01*
X130812D01*
X130866Y562787D01*
G03X156193Y570936I9884J12713D01*
G01X156207Y570985D01*
X163261Y578039D01*
X167544D01*
X167579Y578025D01*
G03X179581Y578089I5921J14975D01*
G01X179617Y578104D01*
X180468D01*
X181793Y576779D01*
Y576549D01*
X181788Y576527D01*
G03X181552Y575226I15713J-3522D01*
G01X181543Y575160D01*
X181089Y574706D01*
X173600D01*
G03X157494Y558600I0J-16106D01*
G01Y554400D01*
G03X160784Y544644I16108J-1D01*
G01X160825Y544591D01*
Y542957D01*
X160820Y542935D01*
G03X160989Y534992I15686J-3640D01*
G01X160996Y534966D01*
Y533791D01*
X159157Y531952D01*
X147442D01*
X143794Y535600D01*
X143784Y535663D01*
G03X133429Y548128I-15796J-2588D01*
G01X133387Y548143D01*
X127653Y553877D01*
G37*
G36*
G01X217706Y499317D02*
Y494956D01*
X216787Y494037D01*
X209929D01*
G03X185340Y487750I-9839J-12748D01*
G03X183265Y487124I3603J-15695D01*
G03X178741Y487089I-2139J-15960D01*
G01X178726Y487087D01*
X170276D01*
X167934Y484745D01*
X163484D01*
Y483178D01*
X159328Y479022D01*
X158194D01*
X158188Y479016D01*
X158100Y479020D01*
G03X157350Y479038I-759J-15984D01*
G01X153752D01*
X149579Y483211D01*
Y495054D01*
X152177Y497652D01*
X191664Y503691D01*
X208374D01*
G03X216381Y500578I9627J12908D01*
G01X216452Y500571D01*
X217706Y499317D01*
G37*
G36*
G01X168100Y845300D02*
X154300D01*
X151763Y847837D01*
Y856400D01*
X153663Y858300D01*
X169763D01*
X170763Y857300D01*
Y847963D01*
X168100Y845300D01*
G37*
G36*
G01X195263Y902165D02*
G03X195037Y900439I2000J-1140D01*
G01X195066Y900328D01*
X194763Y900025D01*
X173263D01*
X172263Y901025D01*
Y908025D01*
X173763Y909525D01*
X194263D01*
X195263Y908525D01*
Y902165D01*
G37*
G36*
G01X169125Y912125D02*
X153575D01*
X152263Y913437D01*
Y926163D01*
X153625Y927525D01*
X169375D01*
X170663Y926237D01*
Y913663D01*
X169125Y912125D01*
G37*
G36*
G01X147500Y945990D02*
Y942615D01*
X142073Y937188D01*
X142047D01*
Y937162D01*
X137262Y932377D01*
Y928603D01*
G02X136579Y928321I-400J0D01*
G01X134323Y930576D01*
X134339Y930676D01*
G03X132010Y941873I-15902J2533D01*
G02X132412Y942483I337J215D01*
G03X145671Y946366I2571J15798D01*
G01X145750Y946437D01*
X147500Y945990D01*
G37*
G36*
G01X197763Y867025D02*
X133689D01*
X131763Y868951D01*
Y895025D01*
X135263Y898525D01*
X193875D01*
X195700Y896700D01*
X200088D01*
X203263Y893525D01*
Y872525D01*
X197763Y867025D01*
G37*
G36*
G01X123586Y910805D02*
X123635Y910854D01*
Y914897D01*
X124763Y916025D01*
X127660D01*
X128660Y915025D01*
Y903422D01*
X127963Y902725D01*
X120463D01*
X119763Y903425D01*
Y906361D01*
G02X120261Y906749I400J0D01*
G03X120656Y906700I393J1552D01*
G01X122256D01*
G03X123858Y908301I0J1602D01*
G01Y909901D01*
G03X123659Y910674I-1601J0D01*
G01X123586Y910805D01*
G37*
G36*
G01X186406Y1383000D02*
G03X186005Y1386605I-16406J0D01*
G01X186000Y1386627D01*
Y1391863D01*
X194335Y1400198D01*
X209248D01*
G03X211437Y1400329I135J16103D01*
G01X211534Y1400342D01*
X211879Y1399998D01*
X250821D01*
X263321Y1412498D01*
X274987D01*
G03X284413I4713J15502D01*
G01X346421D01*
X346423Y1412500D01*
X351795D01*
X356122Y1408173D01*
Y1401378D01*
X366019Y1391481D01*
X391009D01*
X393749Y1388741D01*
Y1383527D01*
X391223Y1381001D01*
X282286D01*
X271499Y1370214D01*
Y1349185D01*
X263440Y1341126D01*
X251753D01*
X251729Y1341132D01*
G03X257927Y1302471I-5194J-20660D01*
G03X271252Y1301084I8608J18001D01*
G01X271275Y1301090D01*
X271499D01*
Y1300786D01*
X282286Y1289999D01*
X403847D01*
X404123Y1289723D01*
X506474D01*
G03X518879Y1296000I-2J15401D01*
G01X524113D01*
G03X536518Y1289723I12407J9124D01*
G01X577123D01*
X593597Y1273249D01*
X625403D01*
X632903Y1280749D01*
X739388D01*
X747948Y1272189D01*
Y1204417D01*
X741733Y1198202D01*
X727550D01*
X676064Y1249688D01*
X204770D01*
X162644Y1291814D01*
Y1354826D01*
X168412Y1360594D01*
X170000D01*
G03X186406Y1377000I0J16406D01*
G01Y1383000D01*
G37*
G36*
G01X262137Y95709D02*
X263363Y96935D01*
X275905Y99600D01*
X278714D01*
G03X281675Y94786I14986J5900D01*
G01Y87908D01*
X276285Y84409D01*
X268955D01*
X267035Y86329D01*
X267020Y86366D01*
G03X262212Y92807I-14820J-6047D01*
G01X262137Y92867D01*
Y95709D01*
G37*
G36*
G01X265927Y407964D02*
X252127D01*
X249590Y410501D01*
Y419064D01*
X251490Y420964D01*
X267590D01*
X268590Y419964D01*
Y410627D01*
X265927Y407964D01*
G37*
G36*
G01X271090Y462289D02*
X270090Y463289D01*
Y470289D01*
X271590Y471789D01*
X292090D01*
X293090Y470789D01*
Y464429D01*
G03X292864Y462703I2000J-1140D01*
G01X292893Y462592D01*
X292590Y462289D01*
X271090D01*
G37*
G36*
G01X295590Y429289D02*
X231516D01*
X229590Y431215D01*
Y457289D01*
X233090Y460789D01*
X291711D01*
X293600Y458900D01*
X297980D01*
X301090Y455789D01*
Y434789D01*
X295590Y429289D01*
G37*
G36*
G01X218290Y464989D02*
X217590Y465689D01*
Y468625D01*
G02X218088Y469013I400J0D01*
G03X218483Y468964I393J1552D01*
G01X220083D01*
G03X221684Y470565I0J1601D01*
G01Y472165D01*
G03X221486Y472938I-1601J2D01*
G01X221413Y473069D01*
X221462Y473118D01*
Y477161D01*
X222590Y478289D01*
X225487D01*
X226487Y477289D01*
Y465686D01*
X225790Y464989D01*
X218290D01*
G37*
G36*
G01X266952Y474789D02*
X251402D01*
X250090Y476101D01*
Y488827D01*
X251452Y490189D01*
X267202D01*
X268490Y488901D01*
Y476327D01*
X266952Y474789D01*
G37*
G36*
G01X397500Y1305000D02*
X288500D01*
X286500Y1307000D01*
Y1364000D01*
X288500Y1366000D01*
X398500D01*
X401248Y1363252D01*
Y1308748D01*
X397500Y1305000D01*
G37*
G36*
G01X405854Y179879D02*
Y178132D01*
X395061Y161512D01*
X391399Y159135D01*
X385496D01*
X381562Y163069D01*
Y167479D01*
X403090Y181460D01*
X404273D01*
X405854Y179879D01*
G37*
G36*
G01X384341Y1009513D02*
X387339Y1012511D01*
X387435Y1012500D01*
G03X404429Y1033875I1815J16000D01*
G03X384796Y1054725I-15179J5375D01*
G01X384769Y1054717D01*
X379346D01*
X375968Y1058095D01*
Y1066831D01*
G03X373139Y1075947I-16106J-1D01*
G01X373104Y1075998D01*
Y1082454D01*
X373149Y1082509D01*
G03X377091Y1093016I-13700J11133D01*
G03X382864Y1103661I-10230J12436D01*
G01X382872Y1103730D01*
X397210Y1118068D01*
X397242Y1118083D01*
G03X421835Y1156692I-18010J38609D01*
G01Y1195192D01*
X437641Y1210998D01*
X566244D01*
X584660Y1192582D01*
Y1156692D01*
G03X603801Y1121131I42604J0D01*
G01X603891Y1121072D01*
Y1116830D01*
X603833Y1116772D01*
G03X599640Y1109257I11454J-11318D01*
G03X596460Y1107109I8233J-15616D01*
G03X576949Y1087320I-3960J-15609D01*
G01X576956Y1087295D01*
Y1081524D01*
G03X587307Y1052150I9044J-13324D01*
G01X587315Y1052151D01*
X592876D01*
G03X595662Y1046831I15411J4681D01*
G03X592181Y1036831I12625J-10001D01*
G01Y1026831D01*
G03X593279Y1020986I16106J0D01*
G03X587695Y1009439I10508J-12205D01*
G02X587264Y1009056I-400J16D01*
G03X586003Y1009106I-1268J-16056D01*
G01X576522D01*
G03X576017Y1010422I-15272J-5106D01*
G02X576242Y1010955I367J159D01*
G03X585021Y1032961I-5742J15045D01*
G03X567464Y1054418I-15121J5539D01*
G01X567449Y1054416D01*
X560229D01*
G03X551080Y1030562I-13729J-8416D01*
G01X551108Y1030570D01*
X553819D01*
X554290Y1030099D01*
Y1027855D01*
X553541Y1027106D01*
X547000D01*
G03X537230Y998195I0J-16106D01*
G01Y992753D01*
X534836Y990359D01*
Y982920D01*
X531758Y979842D01*
X526713D01*
X516035Y990520D01*
X516043Y990613D01*
G03X509269Y1005168I-16043J1387D01*
G01Y1008316D01*
X513350Y1012397D01*
X513431Y1012398D01*
G03X528429Y1033875I-181J16102D01*
G03X508790Y1054723I-15179J5375D01*
G01X508763Y1054715D01*
X506754D01*
X500180Y1061289D01*
Y1066831D01*
G03X499179Y1072420I-16106J0D01*
G01Y1085226D01*
G03X501303Y1093016I-15518J8416D01*
G03X475427Y1109257I-10229J12437D01*
G03X472180Y1107051I8235J-15614D01*
G03X452239Y1088200I-4180J-15551D01*
G01X452243Y1088180D01*
Y1081010D01*
G03X466886Y1052857I9757J-12810D01*
G01X466916Y1052866D01*
X468463D01*
G03X471449Y1046831I15610J3967D01*
G03X467968Y1036831I12625J-10001D01*
G01Y1026831D01*
G03X469066Y1020986I16106J0D01*
G03X463743Y1011744I10508J-12206D01*
G01X461105Y1009106D01*
X453306D01*
X452620Y1009792D01*
Y1011032D01*
X453168Y1011580D01*
X453197Y1011594D01*
G03X460345Y1033315I-7197J14405D01*
G03X440395Y1053901I-15245J5185D01*
G01X440367Y1053892D01*
X436037D01*
G03X426826Y1030637I-14037J-7892D01*
G01X426855Y1030646D01*
X429197D01*
X429839Y1030004D01*
Y1027739D01*
X429206Y1027106D01*
X422500D01*
G03X411704Y999047I0J-16106D01*
G01Y983602D01*
G03X410447Y979629I14595J-6803D01*
G01X403283D01*
X391971Y990941D01*
X391983Y991038D01*
G03X384341Y1006775I-15983J1963D01*
G01Y1009513D01*
G37*
G36*
G01X389482Y1406482D02*
X372233D01*
X371123Y1407592D01*
Y1439212D01*
X372262Y1440351D01*
X395460D01*
X396900Y1438911D01*
Y1413900D01*
X389482Y1406482D01*
G37*
G36*
G01X467968Y121319D02*
G03X469066Y115474I16106J0D01*
G03X465260Y110652I10507J-12207D01*
G01X461982D01*
X458733Y113901D01*
Y123825D01*
G03X460585Y138635I-13233J9176D01*
G01X460572Y138669D01*
Y140067D01*
X462581Y142076D01*
X464761D01*
X468780Y138057D01*
Y136368D01*
X468770Y136338D01*
G03X467968Y131319I15304J-5019D01*
G01Y121319D01*
G37*
G36*
G01X386529Y549576D02*
X387606Y550653D01*
X393804Y551970D01*
X407565D01*
G03X416404Y543092I14935J6030D01*
G01X416441Y543077D01*
X418289Y541229D01*
Y537338D01*
X414894Y533943D01*
X398061Y530369D01*
X395074D01*
X392419Y533024D01*
Y533106D01*
G03X386529Y545479I-16006J-31D01*
G01Y549576D01*
G37*
G36*
G01X599811Y1288250D02*
X597750Y1290311D01*
Y1302811D01*
X595837Y1304724D01*
X536520D01*
G02X536396Y1305504I0J400D01*
G03X531496Y1336222I-4899J14968D01*
G01X511496D01*
G03X506596Y1305504I0J-15750D01*
G02X506472Y1304724I-124J-380D01*
G01X410337D01*
X405250Y1309811D01*
Y1362689D01*
X408750Y1366189D01*
Y1433798D01*
X409952Y1435000D01*
X430000D01*
X441500Y1423500D01*
X484200D01*
X497450Y1410250D01*
X632250D01*
Y1295750D01*
X621689D01*
X619750Y1293811D01*
Y1288811D01*
X619189Y1288250D01*
X599811D01*
G37*
G36*
G01X500180Y161319D02*
G03X499486Y165995I-16106J-1D01*
G01Y180307D01*
G03X501303Y187504I-15825J7823D01*
G03X492901Y215940I-10229J12437D01*
G01X492832Y215948D01*
X490466Y218314D01*
Y221821D01*
X571686Y346890D01*
X601882Y366501D01*
X603464D01*
X603978Y365987D01*
Y364536D01*
X571211Y314076D01*
X570382Y313900D01*
X568094Y310379D01*
Y310378D01*
X560389Y298515D01*
Y298514D01*
X555814Y291470D01*
X555991Y290639D01*
X547588Y277700D01*
X518658Y141589D01*
X514015Y136946D01*
X502257D01*
X499222Y139981D01*
Y145848D01*
X499234Y145881D01*
G03X500180Y151319I-15160J5438D01*
G01Y161319D01*
G37*
G36*
G01X592181Y121319D02*
G03X592550Y117889I16107J-2D01*
G01X592555Y117868D01*
Y114811D01*
X592495Y114753D01*
G03X587695Y103939I11292J-11485D01*
G02X587264Y103556I-400J16D01*
G03X586003Y103606I-1268J-16056D01*
G01X578133D01*
X577592Y104147D01*
Y106043D01*
G03X585021Y127461I-7092J14457D01*
G03X564585Y148201I-15121J5539D01*
G01X564553Y148190D01*
X561300D01*
X559534Y149956D01*
X559525Y149969D01*
G03X554716Y154349I-13024J-9470D01*
G01Y158970D01*
X577333Y265380D01*
X579586Y268849D01*
X582258D01*
X584660Y266447D01*
Y251181D01*
G03X587217Y236644I42601J0D01*
G01Y202744D01*
X584378Y199905D01*
X584356Y199892D01*
G03X576562Y183702I8144J-13892D01*
G01X576564Y183688D01*
Y175749D01*
G03X588107Y146735I9435J-13049D01*
G01X588120Y146737D01*
X589305D01*
X592939Y143103D01*
Y136201D01*
X592930Y136172D01*
G03X592181Y131319I15357J-4854D01*
G01Y121319D01*
G37*
G36*
G01X498527Y1426472D02*
X497815Y1427184D01*
Y1432671D01*
X498999Y1433855D01*
X503299D01*
X505298Y1435854D01*
X505347D01*
X505648Y1436155D01*
X512084D01*
G03X512149Y1436154I57J1600D01*
G01X513549D01*
G03X513614Y1436155I8J1601D01*
G01X515862D01*
X515882Y1436151D01*
G03X516198Y1436120I314J1570D01*
G01X517598D01*
G03X517809Y1436134I0J1601D01*
G01X517907Y1436147D01*
X518199Y1435855D01*
Y1427355D01*
X517316Y1426472D01*
X498527D01*
G37*
G36*
G01X518430Y1437323D02*
X518397Y1437356D01*
X515966D01*
X515150Y1438172D01*
Y1439155D01*
G03X515130Y1439413I-1601J6D01*
G01X515127Y1439429D01*
Y1441266D01*
X515129Y1441281D01*
G03X515148Y1441522I-1583J246D01*
G01Y1443122D01*
G03X515129Y1443363I-1602J-5D01*
G01X515127Y1443378D01*
Y1443893D01*
X513820Y1445200D01*
X506800D01*
X505900Y1446100D01*
Y1449200D01*
X507436Y1450736D01*
X521540D01*
X522612Y1449664D01*
Y1438561D01*
X521374Y1437323D01*
X518430D01*
G37*
G36*
G01X624393Y161319D02*
G03X623679Y166061I-16106J0D01*
G01Y180266D01*
G03X625516Y187504I-15805J7863D01*
G03X631390Y199941I-10229J12437D01*
G01Y200024D01*
X642929Y211563D01*
X642967Y211578D01*
G03X651360Y216048I-15705J39603D01*
G01X651411Y216083D01*
X653222D01*
X654718Y214587D01*
Y208974D01*
X640099Y140197D01*
X636506Y136604D01*
X625859D01*
X622910Y139553D01*
Y144569D01*
X622928Y144609D01*
G03X624393Y151319I-14641J6711D01*
G01Y161319D01*
G37*
G36*
G01X687254Y106120D02*
X687296Y106099D01*
G03X709186Y127106I7204J14401D01*
G03X691511Y148877I-14986J5894D01*
G01X691494Y148874D01*
X685672D01*
X676780Y157766D01*
Y160513D01*
X712715Y329575D01*
X716719Y333579D01*
X725270D01*
X725317Y333550D01*
G03X755077Y328202I21925J36528D01*
G01X755095Y328205D01*
X756881D01*
X758825Y326261D01*
Y322936D01*
X740772Y238006D01*
X725140Y222374D01*
X725109Y222359D01*
G03X715996Y207248I6978J-14512D01*
G01X715999Y207161D01*
X709183Y200345D01*
X709155Y200331D01*
G03X700888Y182053I7345J-14331D01*
G01X700894Y182029D01*
Y175770D01*
G03X712704Y146778I9406J-13070D01*
G01X712719Y146780D01*
X714745D01*
X716883Y144642D01*
Y135257D01*
X716877Y135233D01*
G03X716394Y131319I15623J-3915D01*
G01Y121318D01*
G03X716623Y118612I16106J0D01*
G01X716626Y118595D01*
Y114667D01*
X716568Y114609D01*
G03X712625Y108052I11433J-11339D01*
G01X712610Y108005D01*
X708211Y103606D01*
X694500D01*
G03X681039Y96344I0J-16107D01*
G03X677215Y96014I-537J-16094D01*
G03X675500Y96106I-1719J-16014D01*
G01X670500D01*
G03X665576Y95335I0J-16106D01*
G01X665546Y95325D01*
X664273D01*
X663290Y96308D01*
Y97045D01*
X663841Y99637D01*
X666089Y101885D01*
X666193Y101865D01*
G03X683015Y106075I3887J20182D01*
G01X683070Y106120D01*
X687254D01*
G37*
G36*
G01X614283Y316264D02*
X613062Y317485D01*
Y320401D01*
X637584Y358163D01*
X646005D01*
G03X670332Y371342I8237J13837D01*
G01X670335Y371420D01*
X673017Y374102D01*
X681483D01*
X686186Y369399D01*
Y357024D01*
X679394Y325070D01*
X668280Y313956D01*
X644007D01*
X643969Y313972D01*
G03X617579Y316269I-16706J-39191D01*
G01X617557Y316264D01*
X614283D01*
G37*
G36*
G01X803739Y1295750D02*
X655100D01*
Y1410250D01*
X803589D01*
X804900Y1408939D01*
Y1296911D01*
X803739Y1295750D01*
G37*
G36*
G01X709186Y579606D02*
G03X710004Y588589I-14986J5893D01*
G01X710000Y588608D01*
Y593046D01*
X718025Y601071D01*
G03X726276Y617210I-7726J14128D01*
G01X726264Y617307D01*
X727656Y618699D01*
X729965D01*
X731419Y617245D01*
Y610091D01*
X731405Y610055D01*
G03X730281Y603118I14951J-5982D01*
G01X730287Y603029D01*
X726122Y598864D01*
G03X716394Y584075I6377J-14789D01*
G01Y574075D01*
G03X717183Y569095I16107J-1D01*
G01X717193Y569065D01*
Y567966D01*
X717128Y567907D01*
G03X716025Y566795I10870J-11885D01*
G01X711547D01*
X710428Y567914D01*
Y570627D01*
X710430Y570642D01*
G03X709186Y579606I-15930J2358D01*
G37*
G36*
G01X812000Y1289000D02*
X808001D01*
X806551Y1290451D01*
Y1306526D01*
X806851Y1306826D01*
X812751D01*
X813251Y1306326D01*
Y1290251D01*
X812000Y1289000D01*
G37*
G36*
G01X812500Y1330000D02*
X808000D01*
X807021Y1330980D01*
Y1349032D01*
X807321Y1349332D01*
X813221D01*
X813721Y1348832D01*
Y1331221D01*
X812500Y1330000D01*
G37*
G36*
G01X823000Y1292500D02*
X816000D01*
X815000Y1293500D01*
Y1298500D01*
X816000Y1299500D01*
X823000D01*
X824000Y1298500D01*
Y1293500D01*
X823000Y1292500D01*
G37*
G36*
G01Y1329500D02*
X816000D01*
X815000Y1330500D01*
Y1335500D01*
X816000Y1336500D01*
X823000D01*
X824000Y1335500D01*
Y1330500D01*
X823000Y1329500D01*
G37*
G36*
G01X829500Y1295000D02*
X823000Y1301500D01*
X816000D01*
X815000Y1302500D01*
Y1307000D01*
X814000Y1308000D01*
X813276D01*
X813249Y1308028D01*
X806932D01*
X806411Y1308549D01*
Y1326411D01*
X808000Y1328000D01*
X823500D01*
X825500Y1330000D01*
Y1336500D01*
X824000Y1338000D01*
X816500D01*
X815000Y1339500D01*
Y1350000D01*
X814000Y1351000D01*
X807138D01*
X806922Y1351216D01*
Y1365922D01*
X807500Y1366500D01*
X823500D01*
X825500Y1368500D01*
Y1374500D01*
X823500Y1376500D01*
X817500D01*
X815000Y1379000D01*
Y1387500D01*
X814282Y1388218D01*
X807028D01*
X806667Y1388579D01*
Y1409610D01*
X807754Y1410697D01*
X827803D01*
X832500Y1406000D01*
Y1397000D01*
X834000Y1395500D01*
X836000D01*
X840000Y1399500D01*
X867000D01*
X868500Y1398000D01*
X897121D01*
X907021Y1388100D01*
X952400D01*
X953300Y1387200D01*
Y1364100D01*
X951900Y1362700D01*
X942800D01*
X939900Y1359800D01*
Y1353200D01*
X941404Y1351696D01*
X952698D01*
X952899Y1351495D01*
Y1329601D01*
X954500Y1328000D01*
X963100D01*
X965900Y1325200D01*
Y1295393D01*
X965507Y1295000D01*
X829500D01*
G37*
G36*
G01X868250Y1424672D02*
G03X851636Y1424603I-8250J-13829D01*
G03X834566Y1425356I-9137J-13260D01*
G01X834433Y1425281D01*
X834017Y1425698D01*
X806650D01*
X800082Y1432266D01*
Y1447657D01*
X806723Y1454298D01*
X923779D01*
X928069Y1450008D01*
X928078Y1449942D01*
G03X931010Y1442729I15941J2277D01*
G01X931048Y1442677D01*
Y1436590D01*
X931027Y1436548D01*
G03X930341Y1423653I14388J-7231D01*
G01X930354Y1423619D01*
Y1421175D01*
X927404Y1418225D01*
X920906D01*
X919282Y1419849D01*
X899520D01*
X896532Y1422837D01*
X887245D01*
G03X868250Y1424672I-10745J-11994D01*
G37*
G36*
G01X812500Y1368500D02*
X808001D01*
X806800Y1369702D01*
Y1386700D01*
X807100Y1387000D01*
X813000D01*
X813500Y1386500D01*
Y1369500D01*
X812500Y1368500D01*
G37*
G36*
G01X823000Y1368000D02*
X816000D01*
X815000Y1369000D01*
Y1374000D01*
X816000Y1375000D01*
X823000D01*
X824000Y1374000D01*
Y1369000D01*
X823000Y1368000D01*
G37*
G36*
G01X940500Y1127500D02*
X939500Y1128500D01*
Y1135500D01*
X941500Y1137500D01*
X960500D01*
X964000Y1134000D01*
Y1129746D01*
G03X963206Y1127807I1500J-1746D01*
G01X963214Y1127714D01*
X963000Y1127500D01*
X940500D01*
G37*
G36*
G01X946313Y1079000D02*
X941479Y1083834D01*
Y1098121D01*
X936550Y1103050D01*
Y1110050D01*
X939200Y1112700D01*
X946800D01*
Y1090900D01*
X947850Y1089850D01*
Y1088807D01*
X947846Y1088786D01*
G03X947810Y1088448I1565J-338D01*
G01Y1086848D01*
G03X947846Y1086510I1601J0D01*
G01X947850Y1086489D01*
Y1085650D01*
X950500Y1083000D01*
X954000D01*
X957000Y1086000D01*
X962000D01*
X963000Y1085000D01*
Y1080000D01*
X962000Y1079000D01*
X946313D01*
G37*
G36*
G01X950500Y1085000D02*
X949101Y1086399D01*
Y1090601D01*
X948500Y1091202D01*
Y1113500D01*
X947000Y1115000D01*
X942500D01*
X941000Y1116500D01*
Y1124500D01*
X963300D01*
X963500Y1124300D01*
Y1123300D01*
X963700Y1123100D01*
X967000D01*
X968000Y1124100D01*
Y1128500D01*
X968500Y1129000D01*
X971500D01*
X972000Y1128500D01*
Y1127862D01*
X971989Y1127830D01*
G03X971898Y1127300I1511J-532D01*
G01Y1125900D01*
G03X971989Y1125370I1602J2D01*
G01X972000Y1125338D01*
Y1092500D01*
X970100Y1090600D01*
X959100D01*
X953500Y1085000D01*
X950500D01*
G37*
G36*
G01X1036977Y966843D02*
G03X1016865Y975963I-14897J-6115D01*
G01X1016834Y975952D01*
X1012184D01*
X1004020Y984116D01*
Y1008576D01*
X1018644Y1023200D01*
X1126205D01*
X1139286Y1010119D01*
Y966539D01*
X1137754Y965007D01*
X1131127D01*
X1125250Y970884D01*
G03X1115687Y979478I-14650J-6684D01*
G03X1104434Y983902I-11087J-11678D01*
G03X1077493Y971488I-10846J-11902D01*
G03X1071921Y957849I10470J-12235D01*
G01X1071929Y957756D01*
X1070758Y956585D01*
X1070713Y956570D01*
G03X1063790Y952091I4994J-15309D01*
G01X1063731Y952026D01*
X1060726D01*
G03X1044244Y960903I-14454J-7098D01*
G03X1036977Y966843I-13382J-8957D01*
G37*
G36*
G01X1001242Y1107787D02*
Y1106367D01*
G03X1000970Y1105443I1429J-923D01*
G01Y1102469D01*
X1000170Y1101670D01*
X1000150Y1101658D01*
G03X999642Y1101150I850J-1358D01*
G01X999630Y1101130D01*
X999000Y1100500D01*
Y1097906D01*
X998298Y1097205D01*
Y1097198D01*
X998100Y1097000D01*
X995500D01*
X994700Y1097800D01*
Y1103501D01*
X997944Y1106744D01*
X998582D01*
Y1107383D01*
X998702Y1107502D01*
Y1112998D01*
X998683Y1113016D01*
Y1113684D01*
X998702Y1113702D01*
Y1114398D01*
X1001498D01*
X1001603Y1114504D01*
X1002504D01*
Y1114800D01*
X1004800D01*
X1005000Y1114600D01*
Y1110348D01*
X1004792D01*
Y1109391D01*
X1004698Y1109298D01*
Y1108298D01*
X1004636Y1108236D01*
X1001691D01*
X1001450Y1107994D01*
X1001370D01*
Y1107914D01*
X1001242Y1107787D01*
G37*
G36*
G01X985000Y1130000D02*
X980500Y1134500D01*
Y1150818D01*
X981682Y1152000D01*
X987500D01*
X990000Y1149500D01*
Y1134000D01*
X991298Y1132702D01*
Y1130298D01*
X991000Y1130000D01*
X985000D01*
G37*
G36*
G01X1015500Y1140000D02*
X1010500D01*
X1009500Y1141000D01*
Y1153000D01*
X1012500Y1156000D01*
X1022500D01*
X1028500Y1150000D01*
Y1146000D01*
X1027000Y1144500D01*
X1025000D01*
X1023000Y1146500D01*
X1019500D01*
X1018000Y1145000D01*
Y1142500D01*
X1015500Y1140000D01*
G37*
G36*
G01X1012554Y1101246D02*
X1006188Y1107611D01*
Y1109088D01*
X1006300Y1109200D01*
X1006661D01*
X1006715Y1109159D01*
G03X1007743Y1108814I1027J1356D01*
G01X1010128D01*
X1010602Y1108340D01*
X1010609Y1108268D01*
G03X1012768Y1106109I2391J232D01*
G01X1012840Y1106102D01*
X1014243Y1104699D01*
X1014973D01*
G03X1015845Y1104440I873J1343D01*
G01X1017445D01*
G03X1018317Y1104699I-1J1602D01*
G01X1019706D01*
X1021407Y1106400D01*
X1032294D01*
X1032524Y1106170D01*
Y1103430D01*
X1032294Y1103200D01*
X1029057D01*
X1028897Y1103040D01*
X1022118D01*
X1020324Y1101246D01*
X1012554D01*
G37*
G36*
G01X966000Y1078000D02*
X965000Y1079000D01*
Y1085500D01*
X966500Y1087000D01*
X974500D01*
X975920Y1085580D01*
X975909Y1085484D01*
G03X975898Y1085300I1591J-187D01*
G01Y1083700D01*
G03X975989Y1083170I1602J2D01*
G01X976000Y1083138D01*
Y1079000D01*
X975000Y1078000D01*
X966000D01*
G37*
G36*
G01X980000Y1091000D02*
X977500Y1093500D01*
Y1111000D01*
X979500Y1113000D01*
X992580D01*
Y1112650D01*
X997186D01*
Y1108394D01*
X996932D01*
Y1107432D01*
X993000Y1103500D01*
Y1095500D01*
X988500Y1091000D01*
X980000D01*
G37*
G36*
G01X993216Y1114284D02*
X992000Y1115500D01*
X985500D01*
X984500Y1116500D01*
Y1119500D01*
X984798Y1119798D01*
X987998D01*
X988199Y1120000D01*
X992000D01*
X996932Y1115068D01*
Y1114284D01*
X993216D01*
G37*
G36*
G01X990000Y1123500D02*
X987563Y1121063D01*
X987462Y1121080D01*
G03X987200Y1121102I-265J-1580D01*
G01X985800D01*
G03X985270Y1121011I2J-1602D01*
G01X985238Y1121000D01*
X984500D01*
X982000Y1123500D01*
Y1128000D01*
X982500Y1128500D01*
X989000D01*
X990000Y1127500D01*
Y1123500D01*
G37*
G36*
G01X1004500Y1127200D02*
X1003932Y1126632D01*
X1003800Y1126706D01*
G03X1000665Y1123571I-1129J-2006D01*
G01X1000739Y1123439D01*
X1000600Y1123300D01*
Y1120100D01*
X1000870Y1119831D01*
Y1117555D01*
G03X1001257Y1116439I1801J-1D01*
G01X1001300Y1116384D01*
Y1116000D01*
X998582D01*
Y1116254D01*
X997746D01*
X992500Y1121500D01*
Y1129638D01*
X992511Y1129670D01*
G03X992602Y1130200I-1511J532D01*
G01Y1131800D01*
G03X992511Y1132330I-1602J-2D01*
G01X992500Y1132362D01*
Y1147500D01*
X993500Y1148500D01*
X1003500D01*
X1004500Y1147500D01*
Y1127200D01*
G37*
G36*
G01X1020900Y1298800D02*
X983400D01*
X982200Y1300000D01*
Y1302900D01*
X981100Y1304000D01*
Y1354382D01*
X986918Y1360200D01*
Y1393367D01*
X988776Y1395225D01*
X1016682D01*
X1023718Y1388189D01*
Y1301618D01*
X1020900Y1298800D01*
G37*
G36*
G01X1031007Y1309000D02*
X1028918Y1311089D01*
Y1323689D01*
X1029218Y1323989D01*
X1053422D01*
G03X1056414I1496J1750D01*
G01X1057489D01*
X1058504Y1325004D01*
Y1332088D01*
X1057425Y1333167D01*
X1029762D01*
X1028918Y1334011D01*
Y1351721D01*
X1029296Y1352099D01*
X1053122D01*
G03X1056714I1796J1440D01*
G01X1057999D01*
X1058477Y1352577D01*
Y1358411D01*
X1057569Y1359319D01*
X1056951D01*
G03X1052885I-2033J-1080D01*
G01X1029548D01*
X1028918Y1359949D01*
Y1379830D01*
X1029249Y1380161D01*
X1052940D01*
G03X1056896I1978J1178D01*
G01X1067688D01*
X1071668Y1376181D01*
Y1315168D01*
X1065500Y1309000D01*
X1031007D01*
G37*
G36*
G01X1037500Y1395750D02*
X1026850D01*
X1024000Y1398600D01*
Y1404700D01*
X1026700Y1407400D01*
X1034800D01*
X1038300Y1403900D01*
Y1396550D01*
X1037500Y1395750D01*
G37*
G36*
G01X986900Y1448400D02*
X984400Y1450900D01*
Y1456100D01*
X984900Y1456600D01*
X988300D01*
X990400Y1454500D01*
X992053D01*
G03X994107Y1454480I1047J2050D01*
G01X994148Y1454500D01*
X994500D01*
X995000Y1454000D01*
Y1448900D01*
X994500Y1448400D01*
X986900D01*
G37*
G36*
G01X1184923Y447917D02*
G03X1185630Y442197I16077J-917D01*
G01X1185639Y442168D01*
Y439218D01*
X1182694Y436273D01*
X1182609Y436275D01*
G03X1145556Y415926I-720J-42597D01*
G01X1145498Y415830D01*
X1142286D01*
X1141002Y417114D01*
X1141011Y417207D01*
G03X1141083Y418738I-16334J1535D01*
G01Y431569D01*
G03X1150721Y440322I-5083J15280D01*
G01X1150736Y440356D01*
X1162902Y452522D01*
X1162969Y452531D01*
G03X1176176Y473593I-2069J15969D01*
G01X1176137Y473710D01*
X1180337Y477910D01*
X1180368Y477925D01*
G03X1184700Y480976I-6629J14014D01*
G01X1184981Y481258D01*
X1185005Y481271D01*
G03X1166577Y507489I-7906J14028D01*
G01X1166521Y507440D01*
X1164661D01*
X1158538Y513563D01*
Y529476D01*
X1164912Y535850D01*
X1172044D01*
X1175498Y539304D01*
X1185441D01*
X1197748Y481353D01*
Y467866D01*
G03X1184923Y447917I2752J-15866D01*
G37*
G36*
G01X1162466Y630904D02*
Y622333D01*
X1159644Y619511D01*
X1152889D01*
X1150364Y622036D01*
X1150352Y622094D01*
G03X1134721Y634850I-15752J-3347D01*
G03X1114772Y634410I-9696J-12857D01*
G03X1096755Y614289I-2474J-15912D01*
G01X1096762Y614263D01*
Y611354D01*
X1092045Y606637D01*
X1065651D01*
X1059908Y612380D01*
Y613406D01*
X1060079Y613577D01*
Y619899D01*
X1090047Y649867D01*
X1101562D01*
G03X1116621Y642871I13343J9015D01*
G03X1134087Y654803I1884J15992D01*
G01X1134101Y654855D01*
X1137424Y658178D01*
X1137532Y658152D01*
G03X1144656Y658091I3696J15673D01*
G01X1144791Y658120D01*
X1162466Y630904D01*
G37*
G36*
G01X1071713Y1291200D02*
X1069507Y1293406D01*
Y1309595D01*
X1077113Y1317201D01*
X1098499D01*
X1102500Y1313200D01*
X1122500D01*
X1123500Y1312200D01*
Y1307200D01*
X1122002Y1305702D01*
X1095498D01*
X1089260Y1311940D01*
X1081169D01*
X1079658Y1310429D01*
Y1291895D01*
X1078963Y1291200D01*
X1071713D01*
G37*
G36*
G01X1152128Y833442D02*
G03Y847616I-14682J7087D01*
G03X1153149Y850319I-14681J7090D01*
G01X1153186Y850452D01*
X1176296Y852607D01*
X1192863D01*
X1197310Y848160D01*
Y834608D01*
X1187170Y824468D01*
X1154082D01*
G02X1153684Y824904I0J400D01*
G03X1152128Y833442I-16238J1452D01*
G37*
G36*
G01X1253660Y1008302D02*
G03X1245274Y986986I6340J-14802D01*
G01X1245291Y986947D01*
Y980724D01*
G03X1243240Y977650I12200J-10361D01*
G01X1243213Y977598D01*
X1237023Y973996D01*
X1229472D01*
X1224492Y978976D01*
Y1007622D01*
X1236217Y1019347D01*
X1245123D01*
X1249795Y1014674D01*
X1249802Y1014665D01*
G03X1253660Y1011172I12597J10036D01*
G01Y1008302D01*
G37*
G36*
G01X1194084Y1382365D02*
X1197509Y1385790D01*
X1209479D01*
X1214026Y1381243D01*
Y1365604D01*
X1211291Y1362869D01*
X1196395D01*
X1194028Y1365236D01*
Y1367600D01*
X1194038Y1367630D01*
G03X1194093Y1377340I-15326J4942D01*
G01X1194084Y1377369D01*
Y1382365D01*
G37*
G36*
G01X1317500Y129606D02*
G03Y97394I0J-16106D01*
G01X1327000D01*
G03X1331236Y97961I0J16107D01*
G01X1357460D01*
X1360545Y94876D01*
Y89873D01*
X1358664Y87992D01*
X1351353D01*
X1351331Y87997D01*
G03X1335714Y87913I-7632J-32879D01*
G01X1335691Y87907D01*
X1325870D01*
G03X1314500Y92606I-11370J-11406D01*
G01X1303832D01*
X1296853Y99585D01*
Y114844D01*
G03X1298212Y121319I-14746J6475D01*
G01Y131319D01*
G03X1298209Y131642I-16106J12D01*
G01X1298207Y131727D01*
X1302377Y135897D01*
X1302460D01*
G03X1306307Y136353I42J16103D01*
G03X1327720Y158930I7693J14147D01*
G01Y178964D01*
G03X1313000Y201606I-14720J6536D01*
G01X1307066D01*
X1306003Y202669D01*
Y206987D01*
X1308043Y209027D01*
X1308108Y209037D01*
G03X1336913Y226951I-6237J42144D01*
G01X1336972Y227037D01*
X1339222D01*
X1340854Y225405D01*
X1342883Y219045D01*
X1354175Y145473D01*
Y144514D01*
X1351780Y142119D01*
X1348116D01*
X1348095Y142124D01*
G03X1324589Y129606I-4394J-20078D01*
G01X1317500D01*
G37*
G36*
G01X1270034Y201385D02*
X1265685D01*
X1263322Y203748D01*
X1262536Y213415D01*
X1265119Y215998D01*
X1275166D01*
X1276191Y214973D01*
Y209559D01*
X1276152Y209506D01*
G03X1273459Y203745I12954J-9565D01*
G03X1270090Y201434I8234J-15615D01*
G01X1270034Y201385D01*
G37*
G36*
G01X1270031Y347487D02*
G03X1281346Y342800I11315J11314D01*
G01X1292811D01*
X1299877Y331919D01*
Y325534D01*
X1290055Y315712D01*
X1290006Y315698D01*
G03X1276938Y309326I11864J-40918D01*
G01X1276886Y309288D01*
X1263023D01*
X1254012Y318299D01*
X1250699Y359063D01*
X1252827Y361191D01*
X1256610D01*
G03X1258253Y359265I12958J9390D01*
G01X1270031Y347487D01*
G37*
G36*
G01X1312000Y485394D02*
G03X1322154Y488998I0J16106D01*
G03X1327377Y488756I3347J15752D01*
G01X1327473Y488768D01*
X1329212Y487029D01*
Y431440D01*
X1326599Y428827D01*
X1318359D01*
X1299588Y457732D01*
Y480697D01*
X1304556Y485665D01*
X1304659Y485646D01*
G03X1307496Y485394I2838J15855D01*
G01X1312000D01*
G37*
G36*
G01X1303003Y588904D02*
X1303081Y588907D01*
G03X1306307Y589353I-581J16093D01*
G03X1312180Y587500I7692J14147D01*
G01X1312249Y587492D01*
X1314381Y585360D01*
Y583991D01*
X1311722Y581332D01*
G03X1312235Y551461I6278J-14832D01*
G01X1312275Y551446D01*
X1318394Y545327D01*
Y539500D01*
G03X1319754Y533024I16106J2D01*
G01X1319809Y532899D01*
X1318689Y531779D01*
X1316961D01*
X1316902Y531863D01*
G03X1315962Y533054I-13097J-9370D01*
G03X1301090Y550260I-16062J1147D01*
G01X1301016Y550265D01*
X1294917Y556364D01*
Y564314D01*
G03X1298212Y574075I-12810J9761D01*
G01Y584113D01*
X1303003Y588904D01*
G37*
G36*
G01X1390602Y617593D02*
G03X1390213Y614075I15716J-3518D01*
G01Y604075D01*
G03X1390323Y602200I16106J4D01*
G01X1390324Y602188D01*
Y597940D01*
X1381383Y588999D01*
G03X1383770Y557001I2568J-15896D01*
G01X1383851Y557000D01*
X1385713Y555138D01*
Y549208D01*
X1383847Y547342D01*
X1379545D01*
X1328490Y625959D01*
Y638825D01*
G03X1317171Y658674I-15517J4303D01*
G01X1315451Y660394D01*
Y662317D01*
X1317399Y664265D01*
X1317438Y664280D01*
G03X1344473Y703937I-15568J39657D01*
G01Y708911D01*
X1348671Y713109D01*
X1353584D01*
X1384630Y692948D01*
X1389886Y687692D01*
Y648301D01*
G03X1390602Y632088I16020J-7415D01*
G01Y617593D01*
G37*
G36*
G01X1259485Y741028D02*
X1253761D01*
X1249941Y746910D01*
Y750937D01*
X1252293Y753289D01*
X1252980D01*
X1260168Y751761D01*
X1261452Y750477D01*
Y742995D01*
X1259485Y741028D01*
G37*
G36*
G01X1393722Y175356D02*
Y171355D01*
X1393679Y171301D01*
G03X1390213Y161319I12641J-9982D01*
G01Y151319D01*
G03X1390592Y147846I16106J0D01*
G01Y147749D01*
X1389779Y146936D01*
X1388521D01*
X1388462Y146999D01*
G03X1385668Y149375I-11761J-10999D01*
G01X1385595Y149424D01*
X1373796Y226301D01*
X1371427Y233727D01*
Y235152D01*
X1372603Y236328D01*
X1374030D01*
X1382692Y222990D01*
Y205137D01*
G03X1388285Y187061I15245J-5186D01*
G03X1393661Y175415I17620J1070D01*
G01X1393722Y175356D01*
G37*
G36*
G01X1442473Y130935D02*
Y130369D01*
X1441707Y129603D01*
X1441627Y129601D01*
G03X1426686Y108512I373J-16101D01*
G01Y95944D01*
X1424933Y94191D01*
X1419846D01*
X1417925Y96112D01*
Y103268D01*
G03X1417753Y105615I-16105J0D01*
G01X1417751Y105629D01*
Y109974D01*
X1417808Y110032D01*
G03X1422425Y121319I-11488J11287D01*
G01Y131319D01*
G03X1422411Y131990I-16106J0D01*
G01X1422407Y132077D01*
X1426229Y135899D01*
X1426313Y135898D01*
G03X1430307Y136353I189J16102D01*
G03X1440008Y134523I7692J14147D01*
G01X1440132Y134539D01*
X1442473Y130935D01*
G37*
G36*
G01X1508090Y168797D02*
X1486113Y146820D01*
Y141454D01*
X1486102Y141422D01*
G03X1495379Y121125I15198J-5322D01*
G03X1509143Y103556I16021J-1625D01*
G01X1509209Y103547D01*
X1509925Y102831D01*
Y100388D01*
X1507748Y98211D01*
X1502231D01*
X1500868Y100310D01*
X1498542Y103891D01*
X1497658Y104079D01*
X1450493Y176706D01*
X1450563Y176814D01*
G03X1437000Y201606I-13563J8686D01*
G01X1434323D01*
X1418733Y225613D01*
Y238316D01*
X1426087Y245670D01*
X1432270D01*
X1502587Y200007D01*
X1507097Y195497D01*
X1507087Y195402D01*
G03X1508090Y187867I16013J-1703D01*
G01Y168797D01*
G37*
G36*
G01X1442394Y546471D02*
Y539500D01*
G03X1444236Y532020I16106J-1D01*
G01X1444259Y531977D01*
Y531139D01*
X1443681Y530561D01*
X1441740D01*
X1441682Y530660D01*
G03X1440414Y532510I-13884J-8157D01*
G03X1423304Y550265I-16014J1690D01*
G01X1423214Y550259D01*
X1417925Y555548D01*
Y556025D01*
G03X1417583Y559325I-16106J-1D01*
G01X1417579Y559345D01*
Y562559D01*
X1417638Y562617D01*
G03X1422425Y574075I-11319J11458D01*
G01Y584075D01*
G03X1422375Y585343I-16105J0D01*
G01X1422367Y585435D01*
X1425842Y588910D01*
X1425929Y588907D01*
G03X1430307Y589353I572J16093D01*
G03X1444711Y588862I7693J14147D01*
G01X1444751Y588880D01*
X1452464D01*
X1453982Y587362D01*
Y583684D01*
X1452880Y582582D01*
X1452792Y582587D01*
G03X1452001Y582606I-782J-16087D01*
G01X1442000D01*
G03X1437903Y550924I0J-16106D01*
G01X1437955Y550910D01*
X1442394Y546471D01*
G37*
G36*
G01X1514425Y604075D02*
G03X1514755Y600833I16106J2D01*
G01X1514759Y600813D01*
Y596680D01*
X1505402Y587323D01*
G03X1501138Y584872I5799J-15023D01*
G01X1501083Y584828D01*
X1495486D01*
X1495137Y584902D01*
X1455513Y645918D01*
Y654364D01*
X1457266Y656117D01*
X1461035D01*
X1508906Y625043D01*
X1514813Y619136D01*
Y617588D01*
X1514808Y617567D01*
G03X1514425Y614075I15723J-3491D01*
G01Y604075D01*
G37*
G36*
G01X1541793Y109805D02*
X1541852Y109863D01*
G03X1546637Y121319I-11321J11456D01*
G01Y128213D01*
X1553452Y135028D01*
X1558037D01*
X1558064Y135020D01*
G03X1568206Y135442I4436J15480D01*
G01X1568240Y135455D01*
X1571665D01*
X1573760Y133360D01*
Y122806D01*
G03X1558683Y99048I18366J-28318D01*
G01X1558674Y98981D01*
X1555688Y95995D01*
X1542862D01*
X1542137Y96720D01*
Y103268D01*
G03X1541797Y106559I-16106J-1D01*
G01X1541793Y106579D01*
Y109805D01*
G37*
G36*
G01X1571613Y584338D02*
Y583265D01*
X1570954Y582606D01*
X1566500D01*
G03X1560921Y551391I0J-16106D01*
G01X1560962Y551376D01*
X1566894Y545444D01*
Y539500D01*
G03X1568419Y532659I16105J0D01*
G01X1568438Y532619D01*
Y532465D01*
X1567497Y531524D01*
X1565637D01*
X1565578Y531611D01*
G03X1564580Y532916I-13274J-9117D01*
G03X1547334Y550952I-15980J1983D01*
G01X1547242Y550945D01*
X1542137Y556050D01*
Y556132D01*
G03X1541784Y559375I-16106J-112D01*
G01X1541780Y559396D01*
Y562548D01*
X1541840Y562606D01*
G03X1546637Y574075I-11310J11468D01*
G01Y584076D01*
G03X1546592Y585276I-16106J-3D01*
G01X1546585Y585367D01*
X1550138Y588920D01*
X1550226Y588916D01*
G03X1554807Y589353I777J16084D01*
G03X1566145Y587815I7692J14147D01*
G01X1566228Y587834D01*
X1571613Y584338D01*
G37*
G36*
G01X1678566Y445000D02*
X1677859Y445707D01*
Y452707D01*
X1687859Y462707D01*
X1699859D01*
X1700359Y462207D01*
Y456707D01*
X1702359Y454706D01*
Y450207D01*
X1704359Y448207D01*
Y445707D01*
X1704061Y445408D01*
X1701361D01*
X1700953Y445000D01*
X1678566D01*
G37*
G36*
G01X1731837Y439599D02*
X1731281Y439043D01*
X1719700D01*
X1719547Y439196D01*
X1719560Y439209D01*
Y452908D01*
X1719355D01*
Y456921D01*
X1718996D01*
Y459224D01*
X1719354D01*
Y462157D01*
G03X1720061Y464579I-1495J1751D01*
G01X1720052Y464608D01*
Y466600D01*
X1721716Y468264D01*
G02X1722058Y468123I142J-141D01*
G01Y468106D01*
X1725460D01*
X1725699Y468204D01*
X1727279Y466624D01*
X1727293Y466573D01*
G03X1728412Y465454I1544J425D01*
G01X1728463Y465440D01*
X1731838Y462066D01*
Y459224D01*
X1731996D01*
Y452984D01*
X1731837D01*
Y439599D01*
G37*
G36*
G01X1727155Y469882D02*
X1726896Y470141D01*
X1725460D01*
Y470708D01*
X1722058D01*
Y470141D01*
X1720359D01*
X1718993Y471507D01*
X1718959D01*
Y475204D01*
X1719259Y475504D01*
X1727859D01*
Y475507D01*
X1729401D01*
X1729413Y475320D01*
G03X1730824Y473348I2297J153D01*
G01Y470110D01*
X1730660Y469946D01*
X1730555Y469968D01*
G03X1730237Y470000I-319J-1570D01*
G01X1728837D01*
G03X1728268Y469895I1J-1602D01*
G01X1728234Y469882D01*
X1727155D01*
G37*
G36*
G01X1674359Y427707D02*
X1661359D01*
X1660359Y428707D01*
Y440207D01*
X1661359Y441207D01*
X1674359D01*
X1675359Y440207D01*
Y428707D01*
X1674359Y427707D01*
G37*
G36*
G01X1678859Y428707D02*
X1677359Y430207D01*
Y441707D01*
X1678152Y442500D01*
X1700152D01*
X1701779Y444127D01*
X1701875Y444116D01*
G03X1702059Y444106I179J1591D01*
G01X1703659D01*
G03X1704189Y444196I1J1601D01*
G01X1704221Y444207D01*
X1704859D01*
X1705859Y445207D01*
Y449207D01*
X1706859Y450207D01*
X1709359D01*
X1710235Y451083D01*
X1710357Y451035D01*
G03X1712599Y451350I842J2142D01*
G01X1717844D01*
Y439192D01*
X1707359Y428707D01*
X1678859D01*
G37*
G36*
G01X1685603Y482456D02*
G03X1684539Y482420I9J-16002D01*
G01X1681372D01*
Y482442D01*
X1680560Y483254D01*
Y484622D01*
X1681332Y485394D01*
X1684500D01*
G03X1694654Y488998I0J16106D01*
G03X1714080Y503891I3346J15752D01*
G01X1714084Y503967D01*
X1717749Y507632D01*
X1720989D01*
X1730204Y505673D01*
X1733959Y501918D01*
Y498127D01*
G03X1728109Y491168I8900J-13420D01*
G03X1726034Y490542I3603J-15694D01*
G03X1721510Y490507I-2139J-15960D01*
G01X1721495Y490505D01*
X1713045D01*
X1710703Y488163D01*
X1706253D01*
Y487635D01*
X1704874Y486256D01*
X1703234D01*
X1699434Y482456D01*
X1691900D01*
X1691885Y482458D01*
G03X1686833I-2526J-16004D01*
G01X1686818Y482456D01*
X1685603D01*
G37*
G36*
G01X1808796Y411382D02*
X1794996D01*
X1792459Y413919D01*
Y422482D01*
X1794359Y424382D01*
X1810459D01*
X1811459Y423382D01*
Y414045D01*
X1808796Y411382D01*
G37*
G36*
G01X1813859Y465707D02*
X1812859Y466707D01*
Y473707D01*
X1814359Y475207D01*
X1834859D01*
X1835859Y474207D01*
Y469256D01*
X1835724Y469210D01*
G03X1834319Y466231I752J-2176D01*
G01X1834363Y466110D01*
X1833960Y465707D01*
X1813859D01*
G37*
G36*
G01X1838807Y432707D02*
X1774285D01*
X1772359Y434633D01*
Y460707D01*
X1775859Y464207D01*
X1833737D01*
X1835368Y462576D01*
X1835400D01*
X1835676Y462300D01*
X1837763D01*
X1841200Y458863D01*
Y435100D01*
X1838807Y432707D01*
G37*
G36*
G01X1743655Y450280D02*
X1745256Y451882D01*
X1756509D01*
X1758359Y450032D01*
Y434207D01*
X1753152Y429000D01*
X1745566D01*
X1733859Y440707D01*
Y451207D01*
X1734347Y451695D01*
X1734476Y451630D01*
G03X1735239Y451450I762J1521D01*
G01X1737222D01*
X1738391Y450280D01*
X1743655D01*
G37*
G36*
G01X1763519Y468182D02*
X1763491Y468190D01*
G03X1763032Y468258I-462J-1534D01*
G01X1761632D01*
G03X1761354Y468233I4J-1602D01*
G01X1761251Y468215D01*
X1760359Y469107D01*
Y471859D01*
X1760914Y472414D01*
X1761014Y472399D01*
G03X1761252Y472382I233J1584D01*
G01X1762852D01*
G03X1764454Y473983I0J1602D01*
G01Y475583D01*
G03X1764231Y476397I-1602J-1D01*
G01Y480579D01*
X1765359Y481707D01*
X1768256D01*
X1769696Y480267D01*
Y468882D01*
X1768996Y468182D01*
X1763519D01*
G37*
G36*
G01X1811646Y546679D02*
X1811587Y546770D01*
G03X1792829Y553189I-13488J-8797D01*
G03X1790562Y554096I-7098J-14454D01*
G01Y556024D01*
G03X1789464Y561869I-16106J0D01*
G03X1795062Y574075I-10508J12206D01*
G01Y584075D01*
G03X1795029Y585099I-16106J-6D01*
G01X1795023Y585189D01*
X1798733Y588899D01*
X1798817Y588898D01*
G03X1802807Y589353I185J16102D01*
G03X1824271Y595156I7692J14147D01*
G02X1825011Y594901I343J-207D01*
G03X1825121Y590325I15990J-1905D01*
G01X1825124Y590309D01*
Y587283D01*
X1820447Y582606D01*
X1814500D01*
G03X1813627Y550418I0J-16106D01*
G01X1813703Y550414D01*
X1814894Y549223D01*
Y547493D01*
X1814080Y546679D01*
X1811646D01*
G37*
G36*
G01X1809821Y478207D02*
X1794271D01*
X1792959Y479519D01*
Y492245D01*
X1794321Y493607D01*
X1810071D01*
X1811359Y492319D01*
Y479745D01*
X1809821Y478207D01*
G37*
G36*
G01X1752788Y879500D02*
X1752263Y880025D01*
Y887025D01*
X1762263Y897025D01*
X1774263D01*
X1774763Y896525D01*
Y891025D01*
X1776763Y889024D01*
Y884525D01*
X1778763Y882525D01*
Y880025D01*
X1778440Y879702D01*
X1775502D01*
X1775326Y879525D01*
X1775263D01*
X1775238Y879500D01*
X1752788D01*
G37*
G36*
G01X1802867Y899758D02*
X1806242Y896384D01*
Y893542D01*
X1806400D01*
Y887302D01*
X1806241D01*
Y886202D01*
X1806062Y886023D01*
Y874527D01*
X1806241Y874348D01*
Y873917D01*
X1805685Y873361D01*
X1794104D01*
X1793951Y873514D01*
X1793964Y873527D01*
Y887226D01*
X1793759D01*
Y891239D01*
X1793400D01*
Y893542D01*
X1793758D01*
Y896475D01*
G03X1794465Y898897I-1495J1751D01*
G01X1794456Y898926D01*
Y900918D01*
X1796120Y902582D01*
G02X1796462Y902441I142J-141D01*
G01Y902424D01*
X1799864D01*
X1800103Y902522D01*
X1801683Y900942D01*
X1801697Y900891D01*
G03X1802816Y899772I1544J425D01*
G01X1802867Y899758D01*
G37*
G36*
G01X1794763Y904459D02*
X1793397Y905825D01*
X1793363D01*
Y909522D01*
X1793663Y909822D01*
X1802263D01*
Y909825D01*
X1803805D01*
X1803817Y909638D01*
G03X1805228Y907666I2297J153D01*
G01Y905064D01*
X1804623Y904459D01*
X1799864D01*
Y905026D01*
X1796462D01*
Y904459D01*
X1794763D01*
G37*
G36*
G01X1748763Y862025D02*
X1735763D01*
X1734763Y863025D01*
Y874525D01*
X1735763Y875525D01*
X1748763D01*
X1749763Y874525D01*
Y863025D01*
X1748763Y862025D01*
G37*
G36*
G01X1819159Y863129D02*
X1807752Y874536D01*
Y886013D01*
X1807905Y886168D01*
X1808545D01*
X1808599Y886125D01*
G03X1809643Y885768I1043J1344D01*
G01X1811526D01*
X1813295Y883998D01*
X1819205D01*
X1821406Y886200D01*
X1829913D01*
X1831763Y884350D01*
Y868525D01*
X1831720Y868482D01*
Y864822D01*
X1830027Y863129D01*
X1819159D01*
G37*
G36*
G01X1753263Y863025D02*
X1751763Y864525D01*
Y876025D01*
X1752238Y876500D01*
X1774000D01*
X1775991Y878491D01*
X1776099Y878465D01*
G03X1776463Y878424I360J1560D01*
G01X1778063D01*
G03X1778525Y878492I0J1601D01*
G01X1778553Y878500D01*
X1779238D01*
X1780263Y879525D01*
Y883525D01*
X1781263Y884525D01*
X1783763D01*
X1784639Y885401D01*
X1784761Y885353D01*
G03X1787003Y885668I842J2142D01*
G01X1792248D01*
Y873510D01*
X1781763Y863025D01*
X1753263D01*
G37*
G36*
G01X1814500Y1035106D02*
G03X1811625Y1003153I0J-16106D01*
G01X1811686Y1003142D01*
X1814894Y999934D01*
Y991998D01*
G03X1815845Y986546I16107J1D01*
G01X1815857Y986513D01*
Y984952D01*
X1814873Y983968D01*
X1813675D01*
X1813616Y984056D01*
G03X1813048Y984839I-13313J-9060D01*
G01X1813006Y984893D01*
Y987200D01*
G03X1794947Y1003187I-16106J0D01*
G01X1794851Y1003175D01*
X1790562Y1007464D01*
Y1008780D01*
G03X1789464Y1014625I-16106J0D01*
G03X1795062Y1026831I-10508J12206D01*
G01Y1035557D01*
X1799759Y1040254D01*
X1807126D01*
X1807147Y1040250D01*
G03X1816079Y1040894I3354J15750D01*
G01X1816112Y1040906D01*
X1825724D01*
G03X1827507Y1037212I15275J5096D01*
G01X1827539Y1037162D01*
Y1035988D01*
X1826529Y1034978D01*
X1826433Y1034990D01*
G03X1824505Y1035106I-1930J-15990D01*
G01X1814500D01*
G37*
G36*
G01X1869100Y845900D02*
X1866563Y848437D01*
Y849078D01*
X1866582Y849118D01*
G03X1866563Y851121I-2082J982D01*
G01Y857000D01*
X1868463Y858900D01*
X1884563D01*
X1885563Y857900D01*
Y848563D01*
X1882900Y845900D01*
X1869100D01*
G37*
G36*
G01X1883925Y912725D02*
X1868375D01*
X1867063Y914037D01*
Y926763D01*
X1868425Y928125D01*
X1884175D01*
X1885463Y926837D01*
Y914263D01*
X1883925Y912725D01*
G37*
G36*
G01X1909763Y900025D02*
X1888263D01*
X1887263Y901025D01*
Y908025D01*
X1888763Y909525D01*
X1909263D01*
X1910263Y908525D01*
Y900525D01*
X1909763Y900025D01*
G37*
G36*
G01X1912763Y867025D02*
X1848689D01*
X1846763Y868951D01*
Y895025D01*
X1850263Y898525D01*
X1909600D01*
X1910100Y898025D01*
Y896900D01*
X1910400Y896600D01*
X1915188D01*
X1918263Y893525D01*
Y872525D01*
X1912763Y867025D01*
G37*
G36*
G01X1835624Y902564D02*
X1834763Y903425D01*
Y905755D01*
X1835358Y906350D01*
X1838315D01*
X1838857Y906892D01*
Y908263D01*
G03X1838858Y908301I-1600J61D01*
G01Y909901D01*
G03X1838857Y909939I-1601J-23D01*
G01Y915119D01*
X1839763Y916025D01*
X1842660D01*
X1843928Y914757D01*
Y903345D01*
X1843147Y902564D01*
X1837628D01*
X1837617Y902565D01*
G03X1837436Y902576I-188J-1591D01*
G01X1836036D01*
G03X1835855Y902565I7J-1602D01*
G01X1835844Y902564D01*
X1835624D01*
G37*
%LPC*%
G75*
G36*
G01X78094Y381905D02*
G02X73712Y378215I-12403J10282D01*
G02X43002Y368765I-15003J-5869D01*
G02X42987Y389774I12207J10513D01*
G02X53962Y408595I15740J3432D01*
G02X84202Y414052I15981J-2040D01*
G02X82081Y382031I378J-16106D01*
G02X78094Y381905I-2498J15915D01*
G37*
G36*
G01X431069Y834891D02*
G02X431087Y834795I-15825J-3017D01*
G02X402898Y821531I-12345J-10351D01*
G02X405160Y844448I12344J10352D01*
G02X421526Y868953I13601J8634D01*
G02X434611Y866837I4198J-15553D01*
G02X436975Y865918I-4637J-15428D01*
G02X442525Y866015I3052J-15818D01*
G02X442527Y834185I2501J-15915D01*
G02X433026Y835590I-2501J15915D01*
G02X431426Y835364I-3050J15818D01*
G03X431069Y834891I36J-398D01*
G37*
G36*
G01X307488Y835590D02*
G03X307216Y834946I43J-397D01*
G02X278835Y821419I-12674J-9945D01*
G02X281067Y844582I12207J10513D01*
G02X297551Y869212I13494J8800D01*
G02X310413Y867037I3975J-15612D01*
G02X312996Y866010I-4638J-15428D01*
G02X318026Y866015I2531J-15910D01*
G02X318025Y834185I2499J-15915D01*
G02X308306Y835699I-2498J15915D01*
G02X307488Y835590I-2536J15909D01*
G37*
G36*
G01X1133438Y1474948D02*
G02X1118000Y1464094I-15438J5552D01*
G01X1097567D01*
Y1504561D01*
X1104691Y1511685D01*
X1146957D01*
Y1496679D01*
G02X1146979Y1495848I-16084J-842D01*
G01Y1490848D01*
G02X1133438Y1474948I-16105J0D01*
G37*
G36*
G01X1616072Y833990D02*
X1615990D01*
X1607502Y825502D01*
X1607504Y825416D01*
G02X1576367Y819209I-16104J-416D01*
G02X1576274Y844582I9882J12723D01*
G02X1585683Y868965I13494J8800D01*
G02X1610557Y866204I11318J-11465D01*
G02X1613500Y866015I443J-16104D01*
G02X1616072Y833990I2500J-15915D01*
G37*
G36*
G01X434709Y368249D02*
G02X403335Y368419I-15667J3751D01*
G02X403581Y389724I12207J10513D01*
G01Y395921D01*
X403573Y395948D01*
G02X421826Y416253I15488J4434D01*
G02X432977Y415233I4199J-15553D01*
G02X437858Y413565I-2702J-15882D01*
G02X442514Y413515I2157J-15965D01*
G02X448291Y381827I2499J-15915D01*
G01X448233Y381815D01*
X434722Y368304D01*
X434709Y368249D01*
G37*
G36*
G01X891800Y960491D02*
G02X888201I-1800J16009D01*
G02X872653Y984900I-1801J16009D01*
G02X889800Y996009I15346J-4900D01*
G02X893399I1800J-16009D01*
G02X910077Y986180I1801J-16009D01*
G02X895401Y960491I-12877J-9680D01*
G02X891800I-1801J16009D01*
G37*
G36*
G01X1619296Y381328D02*
X1619238Y381316D01*
X1605013Y367091D01*
X1604998Y367047D01*
G02X1574042Y368664I-15249J5197D01*
G02X1574187Y389854I12208J10512D01*
G01Y396532D01*
X1574181Y396557D01*
G02X1592757Y416456I15587J4069D01*
G02X1603353Y415530I3974J-15612D01*
G02X1609681Y413155I-2371J-15935D01*
G02X1613515Y413015I1333J-16055D01*
G02X1619296Y381328I2498J-15915D01*
G37*
G36*
G01X1498524Y837794D02*
X1498479Y837779D01*
X1480921Y820221D01*
X1480906Y820174D01*
G02X1449829Y821419I-15370J4826D01*
G02X1449858Y842478I12207J10513D01*
G01Y849758D01*
X1449853Y849780D01*
G02X1468544Y869212I15702J3602D01*
G02X1479140Y868286I3974J-15612D01*
G02X1483003Y867206I-2372J-15934D01*
G02X1486705Y867707I3997J-15606D01*
G02X1498524Y837794I6796J-14606D01*
G37*
G54D81*
X83500Y898662D03*
X181327Y460926D03*
X866500Y1392892D03*
X1724096Y464344D03*
X1798500Y898662D03*
G54D79*
X1676511Y1292495D03*
X1155600Y1074500D03*
X836953Y1023500D03*
X1616100Y203786D03*
G54D80*
X61063Y882025D03*
X58263Y885825D03*
Y889225D03*
X87841Y906516D03*
X30563Y871525D03*
X30213Y869275D03*
Y863775D03*
X37813Y869275D03*
X42313D03*
X61063Y876025D03*
X63463D03*
X158890Y444289D03*
X156090Y448089D03*
Y451489D03*
X185668Y468780D03*
X130490Y437389D03*
X131040Y431839D03*
Y426339D03*
X143140D03*
X138640Y431839D03*
X143140D03*
X158890Y438289D03*
X161290D03*
X120636Y904774D03*
X122836D03*
X125441Y906444D03*
X126256Y907901D03*
Y910301D03*
X218463Y467038D03*
X220663D03*
X223268Y468708D03*
X224083Y470165D03*
Y472565D03*
X515798Y1433921D03*
X511749Y1433955D03*
X513949D03*
X517998Y1439521D03*
X517546Y1441122D03*
Y1443522D03*
X945411Y1086448D03*
Y1088848D03*
X951411Y1086448D03*
Y1088848D03*
X989000Y1132200D03*
X973500Y1083300D03*
Y1085700D03*
X985400Y1117700D03*
X987600D03*
X985400Y1123300D03*
X987600D03*
X986000Y1125100D03*
X995000Y1129800D03*
Y1132200D03*
X1701659Y447707D03*
X1698859Y451507D03*
Y454907D03*
X1728437Y472198D03*
X1671159Y437207D03*
X1670809Y434957D03*
Y429457D03*
X1678409Y434957D03*
X1682909D03*
X1701659Y441707D03*
X1704059D03*
X1761232Y470456D03*
X1763432D03*
X1766037Y472126D03*
X1766852Y473583D03*
Y475983D03*
X1776063Y882025D03*
X1773263Y885825D03*
Y889225D03*
X1802841Y906516D03*
X1745563Y871525D03*
X1745213Y869275D03*
Y863775D03*
X1752813Y869275D03*
X1757313D03*
X1776063Y876025D03*
X1778463D03*
X1835636Y904774D03*
X1837836D03*
X1840441Y906444D03*
X1841256Y907901D03*
Y910301D03*
%LPD*%
G75*
G54D10*
G01X646837Y1494200D02*
X634408Y1506629D01*
X517725D01*
X508867Y1497771D01*
G01X735232Y1451210D02*
Y1466931D01*
X727047Y1475116D01*
Y1486003D01*
X718850Y1494200D01*
X646837D01*
G01X735232Y1451210D02*
X739183Y1447259D01*
X757172D01*
X781213Y1471300D01*
X977929D01*
X988707Y1482078D01*
X1002564D01*
X1020500Y1500014D01*
G01X1039900Y1417000D02*
X1040050D01*
X1044850Y1421800D01*
X1047000D01*
G01D02*
Y1434512D01*
X1043606Y1437906D01*
G01X1047000Y1421800D02*
X1048946Y1419854D01*
Y1406365D01*
X1063705Y1391606D01*
X1068125D01*
X1068127Y1391608D01*
X1069431D01*
X1099145Y1361894D01*
X1110106D01*
X1117200Y1354800D01*
Y1346700D01*
G01X1037550Y1475814D02*
Y1469555D01*
X1053882Y1453223D01*
Y1446789D01*
X1061297Y1439374D01*
Y1411483D01*
X1068134Y1404646D01*
X1100283D01*
X1106304Y1410667D01*
X1169152D01*
X1177026Y1402793D01*
X1203312D01*
G01D02*
X1220993D01*
X1239808Y1421608D01*
X1247682D01*
G01D02*
X1248774Y1422700D01*
Y1465400D01*
X1253374Y1470000D01*
G01X1284624Y1476400D02*
X1274624Y1466400D01*
X1256974D01*
X1253374Y1470000D01*
G01X1661626Y1480000D02*
X1663926D01*
X1667426Y1476500D01*
X1774526D01*
X1780226Y1470800D01*
X1788726D01*
X1790226Y1469300D01*
X34900Y34200D03*
X40600Y1464400D03*
X1894200Y1471300D03*
G54D20*
X98000Y904300D03*
X195827Y466564D03*
X662000Y1464000D03*
Y1468000D03*
Y1453500D03*
Y1457500D03*
X1008689Y1092328D03*
X1027687Y1109799D03*
X1738596Y469982D03*
X1812900Y904300D03*
G54D11*
G01X94643Y893374D02*
X97174D01*
X98400Y894600D01*
Y897647D01*
X100310Y899557D01*
G01X75357Y891406D02*
X72282D01*
X68900Y894788D01*
Y897700D01*
G01X94643Y891406D02*
X98006D01*
X100800Y894200D01*
X102600D01*
X106263Y897863D01*
Y900025D01*
G01X75357Y895343D02*
Y896319D01*
X77263Y898225D01*
G01X94643Y887469D02*
X97131D01*
X98400Y886200D01*
X102324D01*
X106363Y890239D01*
Y893425D01*
G01X75357Y893374D02*
X72961D01*
X72063Y894272D01*
Y897142D01*
X73430Y898509D01*
G01X98013Y908025D02*
X101763D01*
X103263Y909525D01*
G01X104026Y904041D02*
X100859D01*
X100600Y904300D01*
X98050D01*
G01X65763Y887525D02*
X65793Y887495D01*
X70603D01*
G01X75357Y887469D02*
X70629D01*
X70603Y887495D01*
G01X112763Y912025D02*
X97763D01*
X94513Y908775D01*
Y908025D01*
G01X88941Y901966D02*
X92216D01*
X94550Y904300D01*
G01D02*
Y907988D01*
X94513Y908025D01*
G01X94643Y895343D02*
Y904207D01*
X94550Y904300D01*
G01X192470Y455638D02*
X194839D01*
X196246Y457045D01*
Y459930D01*
X198137Y461821D01*
G01X173184Y453670D02*
X170109D01*
X166727Y457052D01*
Y459964D01*
G01X192470Y453670D02*
X195348D01*
X198742Y457064D01*
X201427D01*
X204090Y459727D01*
Y462289D01*
G01X173184Y457607D02*
Y458583D01*
X175090Y460489D01*
G01X192470Y449733D02*
X195258D01*
X196427Y448564D01*
X200120D01*
X204190Y452634D01*
Y455689D01*
G01X173184Y455638D02*
X170788D01*
X169890Y456536D01*
Y459406D01*
X171257Y460773D01*
G01X163590Y449789D02*
X163620Y449759D01*
X168430D01*
G01X173184Y449733D02*
X168456D01*
X168430Y449759D01*
G01X213590Y474289D02*
X195590D01*
X192340Y471039D01*
Y470289D01*
G01X186768Y464230D02*
X190043D01*
X192377Y466564D01*
G01D02*
Y470252D01*
X192340Y470289D01*
G01X192470Y457607D02*
Y466471D01*
X192377Y466564D01*
G01X110026Y904041D02*
X114563D01*
G01X104026D02*
Y908762D01*
X103263Y909525D01*
G01X121506Y909101D02*
X118582Y912025D01*
X112763D01*
G01X120496Y1405549D02*
Y1303003D01*
X196999Y1226500D01*
X667400D01*
X717200Y1176700D01*
X831904D01*
X856404Y1201200D01*
X890500D01*
G01X528250Y1470900D02*
X523400D01*
X514500Y1462000D01*
X356030D01*
X330730Y1436700D01*
X173774D01*
X147142Y1410068D01*
Y1285393D01*
X198349Y1234186D01*
X669643D01*
X721129Y1182700D01*
X828347D01*
X854347Y1208700D01*
X873200D01*
G01X893200Y1203660D02*
X855813D01*
X830853Y1178700D01*
X718029D01*
X668229Y1228500D01*
X197828D01*
X125469Y1300859D01*
Y1373872D01*
G01X496500Y1476000D02*
Y1471000D01*
X489500Y1464000D01*
X355201D01*
X329901Y1438700D01*
X169087D01*
X145142Y1414755D01*
Y1284564D01*
X197520Y1232186D01*
X668814D01*
X720300Y1180700D01*
X829371D01*
X847352Y1198681D01*
X847581D01*
X847881Y1198981D01*
G01X136774Y1411000D02*
X138074D01*
X156374Y1429300D01*
Y1430500D01*
G01X130322Y1434014D02*
X120496Y1424188D01*
Y1405549D01*
G01X125469Y1373872D02*
Y1425469D01*
X137574Y1437574D01*
Y1450000D01*
X135174Y1452400D01*
G01X175249Y1434075D02*
X199725D01*
X218300Y1415500D01*
X244400D01*
X256900Y1428000D01*
X279700D01*
G01X207853Y466305D02*
X212390D01*
G01X195840Y470289D02*
X196295Y470744D01*
X200879D01*
G01X195877Y466564D02*
X197827D01*
X198086Y466305D01*
X201853D01*
G01D02*
Y469770D01*
X200879Y470744D01*
G01X219333Y471365D02*
X216409Y474289D01*
X213590D01*
G01X197263Y898275D02*
Y896025D01*
G01Y898775D02*
Y901025D01*
G01X523455Y1416564D02*
X497936D01*
X467000Y1447500D01*
X359500D01*
X340000Y1428000D01*
X279700D01*
G01X295090Y460539D02*
Y458289D01*
G01Y461039D02*
Y463289D01*
G01X516674Y1421605D02*
X518414D01*
X523455Y1416564D01*
G01X662050Y1464000D02*
X663050Y1465000D01*
X664200D01*
X665700Y1463500D01*
G01X675550Y1458721D02*
X677803Y1456468D01*
X678753D01*
X679753Y1457468D01*
Y1459247D01*
X674000Y1465000D01*
X670220D01*
X669470Y1464250D01*
G01X665700Y1463500D02*
X667200Y1465000D01*
X668720D01*
X669470Y1464250D01*
G01X662050Y1468000D02*
X663050Y1467000D01*
X664200D01*
X665700Y1468500D01*
G01X669470Y1467750D02*
X670220Y1467000D01*
X674829D01*
X681753Y1460076D01*
Y1456639D01*
X679582Y1454468D01*
X677802D01*
X675550Y1452216D01*
G01X665700Y1468500D02*
X667200Y1467000D01*
X668720D01*
X669470Y1467750D01*
G01X658550Y1457500D02*
X657550Y1456500D01*
X654163D01*
X652224Y1454561D01*
Y1452395D01*
X650603Y1450774D01*
X646355D01*
X644390Y1452739D01*
Y1464177D01*
X645213Y1465000D01*
X649052D01*
X650000Y1464052D01*
G01D02*
X650948Y1465000D01*
X657550D01*
X658550Y1464000D01*
G01Y1468000D02*
X657550Y1467000D01*
X650948D01*
X650000Y1467948D01*
G01D02*
X649052Y1467000D01*
X644384D01*
X642390Y1465006D01*
Y1451910D01*
X645526Y1448774D01*
X651432D01*
X654224Y1451566D01*
Y1453732D01*
X654992Y1454500D01*
X657550D01*
X658550Y1453500D01*
G01X662050Y1457500D02*
X663050Y1456500D01*
X664200D01*
X665700Y1458000D01*
G01X662050Y1453500D02*
X663050Y1454500D01*
X664200D01*
X665700Y1453000D01*
G01X1193894Y1292533D02*
X1158333D01*
X1143325Y1277525D01*
X918726D01*
X911494Y1270293D01*
X804145D01*
X803928Y1270076D01*
X803927D01*
X803459Y1269608D01*
X803458D01*
X766451Y1232601D01*
Y1216261D01*
X771308Y1211404D01*
X782712D01*
G01Y1206904D02*
X771565D01*
X763451Y1215018D01*
Y1233844D01*
X803773Y1274166D01*
X911124D01*
X917483Y1280525D01*
X1136577D01*
X1151585Y1295533D01*
X1224100D01*
X1227100Y1292533D01*
G01X711500Y1463600D02*
Y1467000D01*
X708600Y1469900D01*
G01X842700Y1071900D02*
X998210D01*
X1008739Y1082429D01*
Y1092328D01*
G01X1205624Y1292533D02*
Y1282358D01*
X1194791Y1271525D01*
X921212D01*
X913980Y1264293D01*
X806631D01*
X772601Y1230263D01*
Y1223511D01*
G01X1238830Y1292533D02*
Y1281483D01*
X1222872Y1265525D01*
X923698D01*
X916466Y1258293D01*
X815869D01*
X780101Y1222525D01*
Y1222267D01*
X778345Y1220511D01*
X778087D01*
X776587Y1219011D01*
X772601D01*
G01X1185324Y1286563D02*
X1158084D01*
X1146046Y1274525D01*
X919969D01*
X912737Y1267293D01*
X805388D01*
X805171Y1267076D01*
X805170D01*
X769451Y1231357D01*
Y1217661D01*
X772601Y1214511D01*
G01X1220450Y1292533D02*
X1196442Y1268525D01*
X922455D01*
X915223Y1261293D01*
X807874D01*
X777101Y1230520D01*
Y1223511D01*
G01X888825Y1208263D02*
X886962Y1206400D01*
X855171D01*
X848181Y1199410D01*
Y1199281D01*
X847881Y1198981D01*
G01X897638Y253937D02*
X894000Y257575D01*
Y306500D01*
X893052Y307448D01*
Y326881D01*
X913702Y347531D01*
X926851D01*
X926978Y347658D01*
X948451D01*
X973231Y372438D01*
X986178D01*
X1027862Y414122D01*
G01X890552Y287008D02*
X883262Y294298D01*
Y328390D01*
X893478Y338606D01*
Y341958D01*
X942836Y391316D01*
X969868D01*
X1010762Y432210D01*
X1028391D01*
X1038067Y441886D01*
G01X943904Y372485D02*
X945408Y373989D01*
Y378761D01*
G01X890552Y296850D02*
X889950D01*
X885262Y301538D01*
Y327119D01*
X911350Y353207D01*
X924499D01*
X926333Y355041D01*
X926460D01*
X943904Y372485D01*
G01X1266914Y1394873D02*
Y1277298D01*
X1238141Y1248525D01*
X946411D01*
X899086Y1201200D01*
X890500D01*
G01X873200Y1208700D02*
X884093D01*
X885930Y1210537D01*
G01X1258187Y1389753D02*
Y1277058D01*
X1235654Y1254525D01*
X943923D01*
X898389Y1208991D01*
X891525D01*
X889979Y1210537D01*
X885930D01*
G01X1253165Y1384633D02*
Y1274865D01*
X1234825Y1256525D01*
X937645D01*
X892460Y1211340D01*
G01X887200Y1216460D02*
X914031Y1243291D01*
G01X1263642Y1392313D02*
Y1276855D01*
X1237312Y1250525D01*
X945582D01*
X898717Y1203660D01*
X893200D01*
G01X1261224Y1387193D02*
Y1277266D01*
X1236483Y1252525D01*
X944752D01*
X899218Y1206991D01*
X898086D01*
X897996Y1206901D01*
X890187D01*
X888825Y1208263D01*
G01X1250347Y1382073D02*
Y1276047D01*
X1232825Y1258525D01*
X934554D01*
X889965Y1213936D01*
G01X1243768Y1376953D02*
X1244236Y1376485D01*
Y1279276D01*
X1227485Y1262525D01*
X928173D01*
X884677Y1219029D01*
G01X952500Y1193300D02*
X942100D01*
G01D02*
X932400D01*
X926700Y1199000D01*
G01X914031Y1243291D02*
X931265Y1260525D01*
X1229984D01*
X1246949Y1277490D01*
Y1379513D01*
G01X941559Y1408198D02*
X943159Y1406598D01*
X958369D01*
X960178Y1408407D01*
Y1418048D01*
X956100Y1422126D01*
Y1447929D01*
X960108Y1451937D01*
X969690D01*
X977338Y1444289D01*
X980012D01*
X982343Y1446620D01*
G01X941559Y1403198D02*
X942959Y1404598D01*
X959198D01*
X962178Y1407578D01*
Y1418877D01*
X958100Y1422955D01*
Y1447100D01*
X960937Y1449937D01*
X968861D01*
X976509Y1442289D01*
X980169D01*
X982343Y1440115D01*
G01X1027862Y414122D02*
X1086335Y472595D01*
Y474758D01*
X1103515Y491938D01*
X1173738D01*
X1177100Y495300D01*
G01X1008739Y1092328D02*
Y1096000D01*
G01X965500Y1124750D02*
Y1122500D01*
G01X1028500Y1118601D02*
X1024843D01*
G01X965500Y1125250D02*
Y1128000D01*
G01X1021216Y1143321D02*
Y1143127D01*
X1030178Y1134165D01*
G01X1021216Y1137321D02*
X1023029D01*
X1026700Y1133650D01*
G01X1022935Y1130028D02*
X1021055D01*
X1019792Y1128765D01*
Y1125492D01*
X1016300Y1122000D01*
X1012900D01*
X1012800Y1122100D01*
G01X1026700Y1133650D02*
X1026050Y1133000D01*
X1024595D01*
X1022935Y1131340D01*
Y1130028D01*
G01X1005239Y1092328D02*
X1000672D01*
X1000000Y1093000D01*
Y1094500D01*
G01D02*
Y1096500D01*
X1002500Y1099000D01*
G01X1002671Y1105443D02*
Y1099171D01*
X1002500Y1099000D01*
G01X1016645Y1106792D02*
X1014708D01*
X1013000Y1108500D01*
G01X1007743Y1110515D02*
X1010985D01*
X1013000Y1108500D01*
G01X1007793Y1114452D02*
X1009352D01*
X1013204Y1118304D01*
X1017700D01*
G01X1026700Y1130150D02*
Y1129082D01*
X1024146Y1126528D01*
X1022935D01*
G01X1021950Y1122400D02*
Y1123350D01*
X1022935Y1124335D01*
Y1126528D01*
G01X1021950Y1122400D02*
Y1119208D01*
X1021343Y1118601D01*
G01D02*
X1021046Y1118304D01*
X1017700D01*
G01X1029000Y1122400D02*
X1025450D01*
G01X969900Y1132800D02*
X971300D01*
X974050Y1130050D01*
X974200D01*
G01D02*
X976640Y1132490D01*
X977643D01*
G01X1004640Y1117605D02*
Y1119140D01*
X1007431Y1121931D01*
Y1122900D01*
G01X1007743Y1112483D02*
X1010700D01*
X1011717Y1113500D01*
X1016300D01*
G01X1024237Y1109799D02*
X1021563Y1112473D01*
Y1114199D01*
G01D02*
X1016999D01*
X1016300Y1113500D01*
G01X1004640Y1105393D02*
Y1104860D01*
X1011379Y1098121D01*
X1013231D01*
G01D02*
X1014682D01*
X1018829Y1093974D01*
X1025474D01*
X1031000Y1099500D01*
G01D02*
X1034225Y1102725D01*
Y1106875D01*
X1031301Y1109799D01*
X1027737D01*
G01X961877Y1445347D02*
X962825Y1444399D01*
X968393D01*
X971061Y1441731D01*
Y1406332D01*
X965400Y1400671D01*
Y1395485D01*
X966985Y1393900D01*
G01X961877Y1441451D02*
X962825Y1442399D01*
X967564D01*
X969061Y1440902D01*
Y1407161D01*
X963400Y1401500D01*
Y1395443D01*
X961857Y1393900D01*
G01X1067712Y1384766D02*
X1062766D01*
X1029025Y1418507D01*
Y1444233D01*
X1015252Y1458006D01*
X999443D01*
G01X1017618Y1460865D02*
X1017657Y1460826D01*
Y1458430D01*
X1031025Y1445062D01*
Y1431657D01*
X1033651Y1429031D01*
Y1416710D01*
X1062731Y1387630D01*
X1068459D01*
X1075030Y1381059D01*
Y1323078D01*
G01X1109593Y932655D02*
X1113448Y928800D01*
X1138000D01*
X1141370Y925430D01*
Y905550D01*
G01X1273874Y1423000D02*
X1260500D01*
X1229529Y1392029D01*
Y1343729D01*
X1216621Y1330821D01*
X1161121D01*
X1125000Y1294700D01*
X1086755D01*
X1082080Y1299375D01*
G01X1126820Y1288500D02*
X1127220Y1288900D01*
X1136238D01*
X1149838Y1302500D01*
X1192900D01*
X1234389Y1343989D01*
Y1391689D01*
X1261700Y1419000D01*
X1275200D01*
X1284000Y1427800D01*
X1343700D01*
X1349100Y1422400D01*
X1644826D01*
X1651399Y1428973D01*
X1651906D01*
G01X1188894Y1346763D02*
X1185546Y1343415D01*
X1163015D01*
X1123600Y1304000D01*
X1092500D01*
X1087005Y1309495D01*
X1082080D01*
G01X1123000Y1297600D02*
X1159221Y1333821D01*
X1185718D01*
G01X1160612Y1401773D02*
X1126112D01*
G01X1222000Y1346700D02*
Y1343922D01*
X1211899Y1333821D01*
X1185718D01*
G01X1659906Y1428973D02*
X1638805Y1407872D01*
X1295302D01*
X1289574Y1413600D01*
X1264801D01*
X1243768Y1392567D01*
Y1376953D01*
G01X1169412Y1396873D02*
X1164512Y1401773D01*
X1160612D01*
G01X1702501Y1434000D02*
X1700301Y1436200D01*
X1663526D01*
X1638036Y1410710D01*
X1328040D01*
X1314375Y1424375D01*
G01X1281624Y1409209D02*
X1274644Y1402229D01*
X1266770D01*
X1253165Y1388624D01*
Y1384633D01*
G01X1663906Y1428973D02*
X1640780Y1405847D01*
X1293527D01*
X1287874Y1411500D01*
X1267200D01*
X1246949Y1391249D01*
Y1379513D01*
G01X1277624Y1409209D02*
X1273894Y1405479D01*
X1266020D01*
X1250347Y1389806D01*
Y1382073D01*
G01X1715953Y457088D02*
X1712878D01*
X1709496Y460470D01*
Y463382D01*
G01X1715953Y461025D02*
Y462001D01*
X1717859Y463907D01*
G01X1715953Y459056D02*
X1713557D01*
X1712659Y459954D01*
Y462824D01*
X1714026Y464191D01*
G01X1715953Y453151D02*
X1711225D01*
X1711199Y453177D01*
G01X1706359Y453207D02*
X1706389Y453177D01*
X1711199D01*
G01X1750622Y469723D02*
X1755159D01*
G01X1735239Y459056D02*
X1737570D01*
X1739096Y460582D01*
Y463429D01*
X1740906Y465239D01*
G01X1735239Y457088D02*
X1738402D01*
X1746859Y465545D01*
Y465707D01*
G01X1735239Y453151D02*
X1737927D01*
X1739096Y451982D01*
X1742950D01*
X1746959Y455991D01*
Y459107D01*
G01X1754525Y478316D02*
X1738968D01*
X1735109Y474457D01*
Y473707D01*
G01X1729537Y467648D02*
X1732812D01*
X1735146Y469982D01*
G01D02*
Y473670D01*
X1735109Y473707D01*
G01X1735239Y461025D02*
Y469889D01*
X1735146Y469982D01*
G01X1762102Y474783D02*
X1758569Y478316D01*
X1754525D01*
G01X1744622Y469723D02*
Y474444D01*
X1743859Y475207D01*
G01X1738609Y473707D02*
X1740109Y475207D01*
X1743859D01*
G01X1744622Y469723D02*
X1741955D01*
X1741696Y469982D01*
X1738646D01*
G01X1809643Y893374D02*
X1812012D01*
X1815363Y896725D01*
Y899504D01*
X1815310Y899557D01*
G01X1790357Y891406D02*
X1787282D01*
X1783900Y894788D01*
Y897700D01*
G01X1809643Y891406D02*
X1812706D01*
X1814200Y892900D01*
X1816600D01*
X1821263Y897563D01*
Y900025D01*
G01X1790357Y895343D02*
Y896319D01*
X1792263Y898225D01*
G01X1809643Y887469D02*
X1812231D01*
X1814000Y885700D01*
X1818500D01*
X1821363Y888563D01*
Y893425D01*
G01X1790357Y893374D02*
X1787961D01*
X1787063Y894272D01*
Y897142D01*
X1788430Y898509D01*
G01X1827863Y912525D02*
X1813263D01*
X1809513Y908775D01*
Y908025D01*
G01X1803941Y901966D02*
X1807116D01*
X1809450Y904300D01*
G01D02*
Y907962D01*
X1809513Y908025D01*
G01X1809643Y895343D02*
Y904107D01*
X1809450Y904300D01*
G01X1813013Y908025D02*
X1814513Y909525D01*
X1818263D01*
G01X1819026Y904041D02*
X1815959D01*
X1815700Y904300D01*
X1812950D01*
G01X1780763Y887525D02*
X1780793Y887495D01*
X1785603D01*
G01X1790357Y887469D02*
X1785629D01*
X1785603Y887495D01*
G01X1836637Y464077D02*
Y462163D01*
G01Y464577D02*
Y466873D01*
X1836476Y467034D01*
G01X1912263Y898275D02*
Y896025D01*
G01X1914500Y902000D02*
X1912263Y899763D01*
Y898775D01*
G01X1825026Y904041D02*
X1829563D01*
G01X1836506Y909101D02*
X1833082Y912525D01*
X1827863D01*
G01X1819026Y904041D02*
Y908762D01*
X1818263Y909525D01*
X59400Y32600D03*
X63374Y1454500D03*
X111024Y39508D03*
Y188130D03*
X173228Y122047D03*
X111024Y492264D03*
Y640886D03*
Y945020D03*
Y1093642D03*
X167716Y1495669D03*
X235236Y39508D03*
Y188130D03*
Y492264D03*
Y640886D03*
Y945020D03*
Y1093642D03*
X246535Y1320472D03*
X266535D03*
X233858Y1495669D03*
X359449Y39508D03*
Y188130D03*
Y492264D03*
Y640886D03*
Y945020D03*
Y1093642D03*
X390757Y1511515D03*
X483661Y39508D03*
Y188130D03*
Y492264D03*
Y640886D03*
Y945020D03*
Y1093642D03*
X503248Y715748D03*
X531535Y1320472D03*
X511535D03*
X548031Y1495669D03*
X607874Y39508D03*
Y188130D03*
X670079Y122047D03*
X607874Y492264D03*
Y640886D03*
Y945020D03*
Y1093642D03*
X614173Y1495669D03*
X732087Y39508D03*
Y188130D03*
Y492264D03*
Y640886D03*
Y945020D03*
Y1093642D03*
X812347Y17406D03*
X885639Y1511515D03*
X1104528Y1162257D03*
X1187163Y158305D03*
X1281693Y39508D03*
Y188130D03*
X1343701Y122046D03*
X1281693Y492264D03*
Y640886D03*
Y945020D03*
Y1093642D03*
X1314960Y1495669D03*
X1405906Y39508D03*
Y188130D03*
Y492264D03*
Y640886D03*
Y945020D03*
Y1093642D03*
X1381102Y1495669D03*
X1530118Y39508D03*
Y188130D03*
Y492264D03*
Y640886D03*
Y945020D03*
Y1093642D03*
X1538001Y1511515D03*
X1654331Y39508D03*
Y188130D03*
X1673917Y262992D03*
X1654331Y492264D03*
Y640886D03*
Y945020D03*
Y1093642D03*
X1695275Y1495669D03*
X1778543Y39508D03*
Y188130D03*
Y492264D03*
Y640886D03*
Y945020D03*
Y1093642D03*
X1761417Y1495669D03*
X1902756Y39508D03*
Y188130D03*
X1840551Y122046D03*
X1902756Y492264D03*
Y640886D03*
Y945020D03*
Y1093642D03*
X1869500Y1461500D03*
G54D21*
X94600Y904300D03*
X192427Y466564D03*
X658600Y1464000D03*
Y1468000D03*
Y1453500D03*
Y1457500D03*
X1005289Y1092328D03*
X1024287Y1109799D03*
X1735196Y469982D03*
X1809500Y904300D03*
G54D30*
X85000Y885500D03*
X182827Y447764D03*
X1725596Y451182D03*
X1800000Y885500D03*
G54D12*
X78000Y44000D03*
X38000Y86000D03*
X86700Y80700D03*
X92250Y80500D03*
X75000Y73300D03*
X92500Y62800D03*
X56750Y62000D03*
X64250Y87500D03*
X95800Y71800D03*
X30500Y67000D03*
X74000Y87500D03*
X89000D03*
X84000D03*
X79000D03*
X81500Y105000D03*
X48000Y160000D03*
X95500Y186000D03*
X89000Y162700D03*
X49500Y140500D03*
X64250Y98500D03*
X73500Y120500D03*
X72900Y133000D03*
X50000Y105500D03*
X54500D03*
X59000D03*
X88000Y204000D03*
X76000Y232000D03*
X50000Y200000D03*
X38000Y348000D03*
X55209Y379278D03*
X58709Y372346D03*
X38000Y418000D03*
Y452000D03*
X69942Y406555D03*
X65692Y392187D03*
X58728Y393206D03*
X84581Y397946D03*
X79581D03*
X88000Y498000D03*
Y478000D03*
X38000Y544000D03*
X81500Y557500D03*
X64250Y551000D03*
X86700Y533200D03*
X75000Y525800D03*
X92250Y533000D03*
X93800Y516800D03*
X64250Y540000D03*
X50000Y558000D03*
X54500D03*
X59000D03*
X53250Y518000D03*
X95500Y525500D03*
X79000Y540000D03*
X84000D03*
X89000D03*
X74000D03*
X40000Y614000D03*
X76000Y642000D03*
X38000Y660000D03*
X95500Y638500D03*
X89000Y615200D03*
X73500Y573000D03*
X72800Y585500D03*
X49500Y593000D03*
X92000Y758000D03*
X34000Y792000D03*
X100000Y800000D03*
X57675Y851609D03*
X53425Y853600D03*
X46461Y853382D03*
X42942Y831932D03*
X46442Y825000D03*
X73526Y850100D03*
X68526D03*
X26000Y908000D03*
Y940000D03*
X88000Y946000D03*
X91114Y909791D03*
X85000Y885500D03*
X89000D03*
Y881500D03*
X85000D03*
X89000Y877500D03*
X85000D03*
X89000Y889500D03*
X85000D03*
X89000Y893500D03*
X85000D03*
X81166Y892754D03*
Y888754D03*
X41263Y887025D03*
X48763D03*
X55763D03*
X51263Y894525D03*
X46763Y891525D03*
X83300Y908900D03*
X100310Y899557D03*
X68900Y897700D03*
X77263Y898225D03*
X83500Y898662D03*
X73430Y898509D03*
X70603Y887495D03*
X66263Y879525D03*
X67763Y883525D03*
X81500Y1010500D03*
X38000Y996000D03*
X73500Y1026000D03*
X72600Y1038400D03*
X49500Y1046000D03*
X86700Y986200D03*
X75000Y978800D03*
X64250Y1004000D03*
X92250Y986000D03*
X95500Y968000D03*
X59000Y1011000D03*
X54500D03*
X50000D03*
X64250Y993000D03*
X53250Y971000D03*
X95500Y972500D03*
X74000Y993000D03*
X89000D03*
X84000D03*
X79000D03*
X50000Y1100000D03*
X95500Y1091500D03*
X89000Y1068200D03*
X50000Y1150000D03*
Y1200000D03*
X100000Y1250000D03*
X50000D03*
Y1300000D03*
X100000D03*
X50000Y1350000D03*
X100000D03*
Y1400000D03*
X50000D03*
X86000Y1444000D03*
X144000Y88000D03*
X111437Y81319D03*
Y66319D03*
X106937Y84370D03*
Y93819D03*
X111437Y51319D03*
X118437Y27697D03*
X148050Y20971D03*
X126900Y39500D03*
X150700Y33100D03*
X157900Y17900D03*
X157600Y24500D03*
X157400Y35800D03*
X183500Y75450D03*
Y80250D03*
X178500Y80000D03*
X185551Y21529D03*
X151200Y48500D03*
Y44400D03*
X145864Y33216D03*
X175650Y28600D03*
X158000Y152000D03*
X154000Y106000D03*
X111437Y161319D03*
Y151319D03*
X173500Y140500D03*
X111437Y131319D03*
Y121319D03*
X127600Y119300D03*
X106937Y103268D03*
X131600Y119100D03*
X174000Y236000D03*
X118437Y199941D03*
X112000Y316000D03*
X162000Y310000D03*
X150000Y350000D03*
X189342Y378932D03*
X192842Y372000D03*
X102000Y440000D03*
X174000Y410000D03*
X178993Y455018D03*
Y451018D03*
X192861Y400482D03*
X182827Y447764D03*
Y455764D03*
X186827D03*
X182827Y451764D03*
X186827D03*
X182827Y439764D03*
Y443764D03*
X188941Y472055D03*
X153590Y449289D03*
X146590D03*
X149090Y456789D03*
X144590Y453789D03*
X139090Y449289D03*
X181127Y471164D03*
X166727Y459964D03*
X175090Y460489D03*
X181327Y460926D03*
X171257Y460773D03*
X168430Y449759D03*
X165590Y445789D03*
X164127Y442264D03*
X156000Y544000D03*
X130000Y560000D03*
X144000Y550000D03*
X152000Y492000D03*
X160000Y508000D03*
X188250Y550951D03*
X106937Y556024D03*
Y537126D03*
Y546575D03*
X111437Y534075D03*
Y519075D03*
Y504075D03*
X118437Y480453D03*
X188250Y540000D03*
X176439Y524992D03*
X182300Y558600D03*
X173600Y554400D03*
Y558600D03*
X178100D03*
X176506Y539295D03*
X180500Y576000D03*
X162000Y614000D03*
X118437Y652697D03*
X111437Y614075D03*
Y604075D03*
Y584075D03*
Y574075D03*
X173500Y593000D03*
X140750Y575500D03*
X143000Y587000D03*
X174000Y686000D03*
X156000Y768000D03*
X150000Y800000D03*
X168937Y850845D03*
X163740Y846722D03*
X159740D03*
X154737Y854845D03*
Y850845D03*
X168937Y854845D03*
X176425Y853700D03*
X180400Y852300D03*
X176558Y831000D03*
X172318Y844782D03*
X169442Y824700D03*
X191026Y850100D03*
X196026D03*
X136000Y912000D03*
X140000Y938000D03*
X188000Y932000D03*
X159860Y924548D03*
X163860D03*
X168863Y916425D03*
Y920425D03*
X118437Y933209D03*
X154663Y916425D03*
Y920425D03*
X173763Y907525D03*
X189763D03*
X185763D03*
X181763D03*
X177763D03*
X193763D03*
X102263Y919025D03*
X114563Y904041D03*
X113763Y865025D03*
X106263Y900025D03*
X106363Y893425D03*
X102207Y890524D03*
X180500Y1028500D03*
X160000Y982000D03*
X142000Y1008000D03*
X140750Y1028500D03*
X174000Y1046000D03*
X111437Y1036831D03*
Y1026831D03*
X188750Y1004000D03*
X111437Y956831D03*
Y986831D03*
Y971831D03*
X106937Y1008780D03*
Y989882D03*
Y999331D03*
X183500Y1011000D03*
X179000D03*
X174500D03*
X188750Y993000D03*
X178200Y977700D03*
X140750Y1039250D03*
X125500Y992500D03*
X136500Y1111500D03*
X164000Y1068000D03*
X118437Y1105453D03*
X111437Y1066831D03*
Y1056831D03*
X158484Y1416000D03*
X139774Y1420600D03*
X131143Y1427661D03*
X130601Y1411700D03*
X136774Y1411000D03*
X188274Y1416600D03*
X165774Y1422700D03*
X157574Y1453500D03*
X145374Y1452500D03*
X145274Y1434685D03*
X156674Y1435085D03*
X167499Y1434000D03*
X104074Y1462500D03*
X114874Y1476700D03*
X118574Y1465900D03*
X121274Y1447400D03*
X124874Y1442600D03*
X151874Y1449800D03*
X149955Y1431573D03*
X135374Y1464000D03*
Y1445500D03*
X105774Y1491000D03*
X120474Y1482800D03*
X132674Y1484200D03*
X137624Y1469000D03*
X175249Y1434075D03*
X156374Y1430500D03*
X130322Y1434014D03*
X135174Y1452400D03*
X104184Y1457200D03*
X139374Y1486100D03*
X124074Y1437200D03*
X113314Y1441700D03*
X262000Y30000D03*
X280000Y90000D03*
X264000Y94000D03*
X202500Y82500D03*
X231000Y82000D03*
X231149Y93819D03*
X235649Y81319D03*
Y66319D03*
X203300Y71700D03*
X215100Y62940D03*
X207000Y80500D03*
X235649Y51319D03*
X242649Y27697D03*
X220000Y80500D03*
X200819Y74819D03*
X217000Y38250D03*
X198800Y34000D03*
X203078Y33972D03*
X215500Y80500D03*
X203000Y87500D03*
X213000D03*
X208000D03*
X197500D03*
X284000Y160000D03*
X256000Y142000D03*
X235649Y161319D03*
Y151319D03*
X219500Y186000D03*
X213500Y162700D03*
X235649Y131319D03*
Y121319D03*
X231149Y103268D03*
X250900Y119500D03*
X197000Y133000D03*
X197500Y120500D03*
X254900Y119600D03*
X198000Y198000D03*
X212000Y236000D03*
X288000Y242000D03*
X250000Y250000D03*
X242649Y199941D03*
X214000Y328000D03*
X250000Y350000D03*
Y300000D03*
X291042Y379232D03*
X286000Y422000D03*
X257567Y409386D03*
X261567D03*
X266764Y417509D03*
Y413509D03*
X252564D03*
Y417509D03*
X199825Y400700D03*
X204075Y398609D03*
X271590Y469789D03*
X275590D03*
X279590D03*
X283590D03*
X287590D03*
X291590D03*
X218214Y397600D03*
X213214D03*
X212390Y466305D03*
X198137Y461821D03*
X204090Y462289D03*
X204190Y455689D03*
X200022Y452941D03*
X212500Y557500D03*
X216000Y498000D03*
X286000Y490000D03*
Y506000D03*
X268000Y544000D03*
X278000Y554000D03*
X266690Y479089D03*
Y483089D03*
X252490D03*
Y479089D03*
X257687Y487212D03*
X261687D03*
X231149Y556024D03*
X232433Y537126D03*
X231149Y546575D03*
X235649Y534075D03*
Y519075D03*
Y504075D03*
X242649Y480453D03*
X210700Y533200D03*
X199000Y525800D03*
X216250Y533000D03*
X218000Y516600D03*
X200090Y481289D03*
X220000Y524000D03*
X203000Y540000D03*
X208000D03*
X213000D03*
X198000D03*
X286000Y612000D03*
X200000Y646000D03*
X242649Y652697D03*
X235649Y614075D03*
X213500Y615200D03*
X219500Y638500D03*
X235649Y604075D03*
Y584075D03*
Y574075D03*
X268187Y578998D03*
X197200Y585500D03*
X197500Y573000D03*
X264750Y586250D03*
X250000Y700000D03*
Y750000D03*
Y850000D03*
Y800000D03*
X291042Y831932D03*
X252000Y906000D03*
X212000Y916000D03*
X213500Y951500D03*
X263500Y939500D03*
X242649Y933209D03*
X197263Y901025D03*
X284500Y982000D03*
X265000Y1008500D03*
X206000Y1010500D03*
X198000Y1026000D03*
X197300Y1038500D03*
X264250Y1028500D03*
X235649Y1036831D03*
Y1026831D03*
X252100Y959100D03*
X211200Y986200D03*
X199500Y978800D03*
X216750Y986000D03*
X231149Y1008780D03*
Y989882D03*
Y999331D03*
X235649Y986831D03*
Y971831D03*
X218100Y969700D03*
X264450Y1039250D03*
X252000Y992500D03*
X220000Y978200D03*
X198500Y993000D03*
X213500D03*
X208500D03*
X203500D03*
X288000Y1068000D03*
X200000Y1100000D03*
X242649Y1105453D03*
X220000Y1091500D03*
X213500Y1068200D03*
X235649Y1066831D03*
Y1056831D03*
X200000Y1200000D03*
X250000D03*
Y1150000D03*
X200000D03*
X227500Y1303000D03*
X250000Y1350000D03*
X209374Y1416300D03*
X259500Y1494000D03*
X256000Y1466000D03*
X386000Y28000D03*
X338000Y30000D03*
Y44000D03*
X355362Y84370D03*
Y93819D03*
X359862Y81319D03*
Y66319D03*
X323500Y73300D03*
X340750Y80500D03*
X335200Y80700D03*
X359862Y51319D03*
X366862Y27697D03*
X341800Y63700D03*
X311800Y83700D03*
X301750Y65500D03*
X340650Y69300D03*
X327500Y87500D03*
X332500D03*
X337500D03*
X322500D03*
X359862Y161319D03*
Y151319D03*
X344000Y186000D03*
X337500Y162700D03*
X298000Y140500D03*
X359862Y131319D03*
X357506Y123493D03*
X355362Y103268D03*
X375500Y119400D03*
X312750Y98500D03*
X322000Y120500D03*
X321500Y133000D03*
X293700Y105500D03*
X298500D03*
X302999Y105501D03*
X379500Y119500D03*
X324000Y196000D03*
X366862Y199941D03*
X358000Y318000D03*
X294542Y372300D03*
X320000Y422000D03*
X336000Y466000D03*
X384000Y468000D03*
X305775Y398909D03*
X301525Y400900D03*
X294561Y400682D03*
X320514Y397600D03*
X315514D03*
X295090Y463289D03*
X338000Y498000D03*
X355362Y556024D03*
Y537126D03*
Y546575D03*
X312750Y551000D03*
X359862Y534075D03*
Y519075D03*
Y504075D03*
X366862Y480453D03*
X335200Y533200D03*
X323500Y525800D03*
X340750Y533000D03*
X341800Y516800D03*
X312750Y536300D03*
X299104Y556943D03*
X303604D03*
X308104D03*
X301750Y518000D03*
X344000Y525300D03*
X322500Y540000D03*
X337500D03*
X332500D03*
X327500D03*
X324000Y650000D03*
X359862Y614075D03*
X366862Y652697D03*
X344000Y638500D03*
X337500Y615200D03*
X359862Y604075D03*
Y584075D03*
X374261Y572963D03*
X322000Y573000D03*
X323380Y589452D03*
X298000Y593000D03*
X334000Y686000D03*
X342000Y758000D03*
X350000Y850000D03*
Y800000D03*
X301525Y853600D03*
X305775Y851609D03*
X294561Y853382D03*
X294542Y825000D03*
X320526Y850100D03*
X315526D03*
X337500Y946500D03*
X359500Y925400D03*
X330000Y1010500D03*
X304500Y1028500D03*
X359862Y1036831D03*
Y1026831D03*
X322000Y1026000D03*
X321200Y1038500D03*
X298000Y1046000D03*
X358800Y955900D03*
X355362Y1008780D03*
Y989882D03*
Y999331D03*
X359862Y986831D03*
Y971831D03*
X335200Y986200D03*
X323500Y978800D03*
X312750Y1004000D03*
X340750Y986000D03*
X341900Y969400D03*
X307500Y1011000D03*
X303000D03*
X298500D03*
X312750Y993000D03*
X302100Y978200D03*
X376000Y993000D03*
X344200Y978200D03*
X322500Y993000D03*
X337500D03*
X332500D03*
X327500D03*
X318000Y1058000D03*
X326000Y1106000D03*
X366862Y1105453D03*
X359862Y1066831D03*
Y1056831D03*
X344000Y1091500D03*
X337500Y1068200D03*
X300000Y1200000D03*
Y1150000D03*
X373492Y1317441D03*
Y1322441D03*
Y1327441D03*
Y1332441D03*
X343688Y1317736D03*
Y1322736D03*
Y1327736D03*
Y1332736D03*
X313688D03*
Y1327736D03*
Y1322736D03*
Y1317736D03*
Y1312736D03*
X369086Y1313208D03*
X374086D03*
X379086D03*
X384086D03*
X324086D03*
X329086D03*
X334086D03*
X339086D03*
X344086D03*
X349086D03*
X354086D03*
X359086D03*
X364086D03*
X294086D03*
X299086D03*
X304086D03*
X309086D03*
X319086D03*
X350000Y1400000D03*
X373492Y1337441D03*
Y1342441D03*
Y1347441D03*
Y1352441D03*
X343688Y1337736D03*
Y1342736D03*
Y1347736D03*
Y1352736D03*
X313688D03*
Y1347736D03*
Y1342736D03*
Y1337736D03*
X323688Y1357736D03*
X328688D03*
X333688D03*
X338688D03*
X343688D03*
X348688D03*
X353688D03*
X358688D03*
X363688D03*
X368688D03*
X373688D03*
X378688D03*
X383688D03*
X298688D03*
X303688D03*
X308688D03*
X313688D03*
X318688D03*
X293688D03*
X300000Y1400000D03*
X410679Y31098D03*
X414000Y58000D03*
X402000Y64000D03*
X454000Y83800D03*
X479574Y84370D03*
Y93819D03*
X462100Y62940D03*
X450300Y71700D03*
X425500Y72600D03*
X435500D03*
X430500D03*
X440500D03*
X468500Y80500D03*
X465500Y38250D03*
X425500Y41250D03*
X430500D03*
X434804Y41242D03*
X444663Y32417D03*
X440400Y32400D03*
X464000Y80500D03*
X446400Y91100D03*
X456900D03*
X461900D03*
X451900D03*
X467500Y116000D03*
X394000Y164000D03*
Y174000D03*
X462000Y162700D03*
X468000Y186000D03*
X422000Y140500D03*
X479574Y103268D03*
X441300Y126000D03*
X445500Y133000D03*
X440849Y111648D03*
X437500Y134500D03*
X441500D03*
X433500D03*
X430083Y122357D03*
X388000Y196000D03*
X416000D03*
X400000Y350000D03*
X415542Y378932D03*
X419042Y372000D03*
X428000Y430000D03*
X460000Y468000D03*
X426025Y400700D03*
X419061Y400382D03*
X430275Y399351D03*
X445014Y397600D03*
X440014D03*
X402000Y560000D03*
X388000Y548000D03*
X410000Y544000D03*
X392000Y490000D03*
X460000Y496000D03*
X479574Y556024D03*
Y537126D03*
Y546575D03*
X436750Y551000D03*
X459200Y533200D03*
X446993Y527868D03*
X464750Y533000D03*
X466000Y516900D03*
X436750Y538400D03*
X422500Y558000D03*
X427000D03*
X431500D03*
X429210Y512992D03*
X464801Y521156D03*
X446500Y540000D03*
X461500D03*
X456500D03*
X451500D03*
X410000Y616000D03*
X468000Y638500D03*
X467029Y610775D03*
X441641Y574141D03*
X445546Y586021D03*
X421820Y593641D03*
X389250Y575500D03*
X390632Y588624D03*
X422000Y684000D03*
X454000Y686000D03*
X466000Y762000D03*
X400000Y800000D03*
X425725Y853400D03*
X429975Y851409D03*
X418761Y853082D03*
X415242Y831882D03*
X418742Y824444D03*
X440026Y850100D03*
X445026D03*
X387500Y939000D03*
X462000Y947000D03*
X428500Y1028500D03*
X454000Y1010500D03*
X407000Y984000D03*
X389500Y1009000D03*
X446000Y1026000D03*
X445100Y1038500D03*
X389250Y1028500D03*
X422000Y1046000D03*
X459200Y986200D03*
X447500Y978800D03*
X436750Y1004000D03*
X464750Y986000D03*
X479574Y1008780D03*
Y989882D03*
Y999331D03*
X466100Y969200D03*
X431500Y1011000D03*
X427000D03*
X422500D03*
X436750Y993000D03*
X426300Y976800D03*
X389250Y1039250D03*
X468300Y978000D03*
X446500Y993000D03*
X461500D03*
X456500D03*
X451500D03*
X448000Y1106000D03*
X410000Y1068000D03*
X468000Y1091500D03*
X462000Y1068200D03*
X450000Y1150000D03*
Y1200000D03*
X389086Y1313208D03*
X394086D03*
X390500Y1386000D03*
X388688Y1357736D03*
X393688D03*
X532000Y90000D03*
X534000Y58000D03*
X512000Y28000D03*
X572000Y73300D03*
X484074Y81319D03*
Y66319D03*
Y51319D03*
X491074Y27697D03*
X561250Y87500D03*
X550250Y65500D03*
X576000Y87500D03*
X571000D03*
X556000Y156000D03*
X568000Y190000D03*
X544000Y160000D03*
X502500Y139500D03*
X512000Y104000D03*
X546500Y140500D03*
X484074Y161319D03*
Y151319D03*
X561250Y98500D03*
X570500Y120500D03*
X569900Y133000D03*
X499900Y119400D03*
X484074Y131319D03*
Y121319D03*
X547000Y105500D03*
X551500D03*
X556000D03*
X503900Y119500D03*
X534000Y222500D03*
X493000Y218500D03*
X491074Y199941D03*
X539742Y379232D03*
X543242Y372300D03*
Y400682D03*
X550225Y400900D03*
X554475Y399651D03*
X569014Y397600D03*
X564014D03*
X516000Y488000D03*
X574000D03*
X524000Y560000D03*
X561250Y551000D03*
X572000Y525800D03*
X484074Y504075D03*
X491074Y480453D03*
X483513Y535912D03*
X484074Y519075D03*
X561250Y540000D03*
X550250Y518000D03*
X571000Y540000D03*
X576000D03*
X536000Y644000D03*
X510000Y656000D03*
X491074Y652697D03*
X484074Y614075D03*
X565279Y578552D03*
X569900Y585500D03*
X551276Y597925D03*
X483265Y606243D03*
X484074Y584075D03*
Y574075D03*
X513250Y574252D03*
X516000Y637413D03*
X546500Y572000D03*
X551044Y572149D03*
X555321Y572375D03*
X517999Y583015D03*
X552000Y686000D03*
X542000Y764000D03*
X500000Y800000D03*
Y850000D03*
X564026Y850100D03*
X569026D03*
X512000Y939000D03*
X483549Y925564D03*
X513500Y1009000D03*
X532000Y983000D03*
X553000Y1028500D03*
X570500Y1026000D03*
X569900Y1038500D03*
X546500Y1046000D03*
X513250Y1028500D03*
X484074Y1036831D03*
Y1026831D03*
X572000Y978800D03*
X561250Y1004000D03*
X499800Y956831D03*
X484074Y986831D03*
Y971831D03*
X556000Y1011000D03*
X551500D03*
X547000D03*
X561250Y993000D03*
X550700Y979500D03*
X513250Y1039250D03*
X500000Y992000D03*
X571000Y993000D03*
X576000D03*
X534000Y1068000D03*
X550000Y1100000D03*
X491074Y1105453D03*
X484074Y1066831D03*
Y1056831D03*
X500000Y1150000D03*
X550000D03*
Y1200000D03*
X500000D03*
X522000Y1294000D03*
X505224Y1424156D03*
X523455Y1416564D03*
X524236Y1463672D03*
X542066Y1440238D03*
X537466D03*
X532866D03*
X528798Y1437733D03*
X524722Y1436362D03*
X528500Y1444600D03*
X507250Y1478000D03*
X535200Y1466100D03*
X523500Y1455400D03*
X503001Y1454922D03*
X513624Y1458624D03*
X504000Y1470500D03*
X503035Y1444331D03*
X528250Y1470900D03*
X496500Y1476000D03*
X508867Y1497771D03*
X585500Y45000D03*
X650000Y84000D03*
X578000Y52000D03*
X592500Y28000D03*
X603787Y84370D03*
Y93819D03*
X608287Y81319D03*
Y66319D03*
X589250Y80500D03*
X583700Y80700D03*
X608287Y51319D03*
X615287Y27697D03*
X590600Y64300D03*
X670500Y80000D03*
X589150Y69500D03*
X581000Y87500D03*
X586000D03*
X638000Y104000D03*
X654000Y162500D03*
X664500Y97000D03*
X579000Y105000D03*
X670500Y140500D03*
X608287Y161319D03*
Y151319D03*
X592500Y186000D03*
X586000Y162700D03*
X608287Y131319D03*
Y121319D03*
X603787Y103268D03*
X624000Y119400D03*
X626000Y140000D03*
X628000Y119500D03*
X652000Y214000D03*
X582500Y266000D03*
X615287Y199941D03*
X586500Y292000D03*
X643000Y317500D03*
X614500Y318500D03*
X639000Y354500D03*
X602500Y365000D03*
X650742Y378932D03*
X654242Y372000D03*
X661225Y400738D03*
X654261Y400382D03*
X665475Y399378D03*
X638000Y488000D03*
X644000Y558000D03*
X603787Y556024D03*
Y537126D03*
Y546575D03*
X608287Y534075D03*
Y519075D03*
Y504075D03*
X615287Y480453D03*
X589250Y533000D03*
X583700Y533200D03*
X583550Y504600D03*
X672018Y557014D03*
X592500Y525300D03*
X586000Y540000D03*
X581000D03*
X664651Y513000D03*
X671000Y648000D03*
X672500Y615500D03*
X615287Y652697D03*
X622687Y614091D03*
X592500Y638500D03*
X586043Y615962D03*
X670500Y593000D03*
X622703Y604103D03*
X623005Y584047D03*
X608287Y574075D03*
X637750Y575500D03*
X666900Y665400D03*
X637750Y586250D03*
X590000Y680000D03*
X646680Y679430D03*
X600000Y770000D03*
X650000D03*
X624000Y846000D03*
X579148Y832411D03*
X666625Y853400D03*
X670875Y851409D03*
X589805Y854600D03*
X594055Y852609D03*
X659661Y853082D03*
X582667Y853605D03*
X656142Y831632D03*
X582648Y825223D03*
X659642Y824700D03*
X585000Y948000D03*
X636000Y939000D03*
X615287Y933209D03*
X585904Y900960D03*
X589904D03*
X593904D03*
X597904D03*
X601904D03*
X673000Y885500D03*
X578000Y1010500D03*
X652500Y984500D03*
X625000Y1014500D03*
X653500Y997500D03*
X670500Y1046000D03*
X637750Y1028500D03*
X608287Y1036831D03*
Y1026831D03*
X601800Y955500D03*
X589250Y986000D03*
X603787Y1008780D03*
Y989882D03*
Y999331D03*
X608287Y986831D03*
Y971831D03*
X583700Y986200D03*
X590200Y969500D03*
X671000Y1011000D03*
X624500Y993000D03*
X592800Y978100D03*
X586000Y993000D03*
X581000D03*
X599000Y1115500D03*
X631500Y1112500D03*
X660000Y1068000D03*
X615287Y1105453D03*
X592500Y1091500D03*
X608287Y1066831D03*
Y1056831D03*
X586000Y1068200D03*
X672000Y1146000D03*
X670000Y1196000D03*
X668000Y1418900D03*
X672000Y1419000D03*
X637971Y1425400D03*
X657836Y1433318D03*
X658000Y1449200D03*
X653000Y1488500D03*
X650000Y1464052D03*
Y1467948D03*
Y1457448D03*
Y1453552D03*
X636250Y1468500D03*
X628500D03*
X637972Y1441419D03*
X658000Y1444000D03*
X624750Y1461250D03*
X729201Y87285D03*
X727636Y93834D03*
X732500Y81319D03*
Y66319D03*
X704000Y80500D03*
X699500Y82500D03*
X700300Y71700D03*
X712000Y62940D03*
X732500Y51319D03*
X739500Y27697D03*
X712214Y82500D03*
X680500Y80250D03*
X675500Y80000D03*
X697787Y74488D03*
X714000Y38250D03*
X695600Y34000D03*
X699932Y34034D03*
X709000Y79500D03*
X700000Y87500D03*
X705000D03*
X710000D03*
X694500D03*
X711352Y26875D03*
X715205Y27012D03*
X705171Y16254D03*
X681000Y171500D03*
X732500Y161319D03*
Y151319D03*
X716500Y186000D03*
X710300Y162700D03*
X747290Y118820D03*
X732500Y131319D03*
Y121319D03*
X728000Y103268D03*
X694500Y120500D03*
X694200Y133000D03*
X753473Y138459D03*
X714000Y240000D03*
X700000Y200000D03*
X732087Y207847D03*
X756000Y326000D03*
X718000Y332000D03*
X704500Y408500D03*
X685514Y397600D03*
X680514D03*
X716000Y568500D03*
X688000Y496000D03*
X728000Y556024D03*
Y537126D03*
Y546575D03*
X688298Y551625D03*
X732500Y504075D03*
X707700Y533200D03*
X696000Y525800D03*
X732500Y519075D03*
X713250Y533000D03*
X732500Y534075D03*
X724600Y487100D03*
X698600Y511100D03*
X685250Y540000D03*
X680902Y557860D03*
X676402D03*
X674250Y518000D03*
X714600Y498100D03*
X716400Y525200D03*
X695000Y540000D03*
X700000D03*
X705000D03*
X710000D03*
X747843Y612115D03*
X739500Y652697D03*
X710300Y635400D03*
Y615200D03*
X748200Y572200D03*
X732500Y574075D03*
X694200Y585500D03*
X732500Y584075D03*
X694500Y573000D03*
X746356Y604075D03*
X752200Y572300D03*
X710000Y760500D03*
X726500Y681500D03*
X693500Y680000D03*
X712000Y720000D03*
X709871Y686246D03*
X718100Y738500D03*
X718200Y744000D03*
X723000Y739200D03*
X723300Y743700D03*
X728175Y741300D03*
X728100Y745500D03*
X680526Y850100D03*
X685526D03*
X710000Y950500D03*
X739500Y933209D03*
X701700Y872700D03*
X714500Y870100D03*
X723600Y872400D03*
X712760Y915137D03*
X727600Y872300D03*
X733895Y901054D03*
X754000Y884524D03*
X757600Y884400D03*
X677000Y885500D03*
Y1028500D03*
X702500Y1010500D03*
X753050Y1028500D03*
X694500Y1026000D03*
X694000Y1038500D03*
X732500Y1036831D03*
Y1026831D03*
X730900Y955800D03*
X707700Y986200D03*
X696000Y978800D03*
X685250Y1004000D03*
X713250Y986000D03*
X728000Y1008780D03*
Y989882D03*
Y999331D03*
X732500Y986831D03*
Y971831D03*
X714400Y969600D03*
X680000Y1011000D03*
X675500D03*
X685250Y993000D03*
X675400Y980500D03*
X755200Y992400D03*
X716800Y978300D03*
X700000Y993000D03*
X705000D03*
X710000D03*
X695000D03*
X759249Y1008800D03*
X750000Y1084000D03*
X698000Y1102000D03*
X739500Y1105453D03*
X716500Y1091500D03*
X710300Y1068200D03*
X732500Y1066831D03*
Y1056831D03*
X759700Y1138600D03*
X759762Y1135000D03*
X738000Y1152000D03*
X740000Y1202000D03*
X748000Y1170000D03*
X746000Y1218000D03*
X700000Y1150000D03*
X698500Y1418900D03*
X693000Y1418800D03*
X689000Y1419000D03*
X681000Y1419100D03*
X685000Y1418900D03*
X703500Y1426000D03*
X676500Y1419500D03*
X742880Y1422632D03*
X739532Y1425934D03*
X720455Y1438500D03*
X684000Y1482000D03*
X699500Y1476000D03*
X685000Y1453500D03*
X690000Y1448500D03*
X695000Y1453500D03*
X690000Y1458500D03*
Y1453500D03*
X724248Y1465560D03*
X730500Y1451500D03*
X685850Y1468600D03*
X724000Y1439700D03*
X717600Y1449700D03*
X746832Y1451034D03*
X735232Y1439334D03*
X739332Y1462234D03*
X750867Y1438001D03*
X722200Y1476900D03*
X680900Y1469200D03*
X680200Y1465500D03*
X675550Y1458721D03*
Y1452216D03*
X692000Y1471156D03*
X689250Y1433500D03*
X681250D03*
X745000Y1463000D03*
X730341Y1446725D03*
X756332Y1465934D03*
X745032Y1468534D03*
X732232Y1477094D03*
X718900Y1472800D03*
X679800Y1483500D03*
X708600Y1469900D03*
X724066Y1461018D03*
X724255Y1457253D03*
X735232Y1451210D03*
X771500Y251000D03*
X802000Y263500D03*
X804500Y379000D03*
X769500Y431500D03*
X807500Y473700D03*
X835165Y470414D03*
X787971Y466121D03*
X791971D03*
X787971Y461921D03*
X791971D03*
X787971Y457721D03*
X791971D03*
X848799Y457202D03*
X849539Y453596D03*
X827313Y464805D03*
X827361Y459317D03*
X860519Y428234D03*
X860716Y417600D03*
X850947Y417592D03*
X832417Y459017D03*
X812282Y448094D03*
X815255Y451343D03*
X808395Y454315D03*
X834000Y499000D03*
X858740Y486430D03*
X846950Y645820D03*
Y640820D03*
X822841Y662242D03*
X794883Y639984D03*
X798475Y640227D03*
X863430Y618590D03*
X788160Y666220D03*
X814320Y651120D03*
X813980Y647430D03*
X860360Y605900D03*
X836862Y637500D03*
X815148Y654937D03*
X824618Y614617D03*
X827750Y611798D03*
X791530Y614700D03*
X791680Y619050D03*
X799900Y636300D03*
X807440Y629910D03*
X802900Y634000D03*
X839400Y744920D03*
X859664Y683428D03*
X837709Y681095D03*
X789442Y681063D03*
X796200Y682400D03*
X791243Y668081D03*
X778627Y735644D03*
X778683Y745049D03*
X853900Y839200D03*
X833300Y856920D03*
X841309Y796644D03*
X841800Y804499D03*
X854973Y780437D03*
X810700Y776500D03*
X818162Y819005D03*
X810659Y767500D03*
X778735Y839888D03*
X791500Y764500D03*
X795300Y764900D03*
X826000Y857400D03*
X815469Y811029D03*
X815330Y807050D03*
X818113Y814998D03*
X834200Y796220D03*
X810700Y772000D03*
Y781000D03*
X804200Y798200D03*
X811372Y795900D03*
X808372Y797900D03*
X805372Y801700D03*
X834470Y944430D03*
X842270Y942411D03*
X818434Y919985D03*
X820883Y879428D03*
X820900Y888500D03*
X825900Y862040D03*
X801300Y924300D03*
X799303Y927296D03*
X822463Y920345D03*
X842270Y936402D03*
X861300Y895300D03*
X819000Y896100D03*
X817337Y886075D03*
X815400Y892800D03*
X826000Y1004000D03*
X846500Y997500D03*
X827000Y985500D03*
X796301Y959795D03*
X822470Y981470D03*
X839970D03*
X834470D03*
X826470D03*
X848400Y974100D03*
X836953Y1023500D03*
X826000Y1062000D03*
X846500Y1055000D03*
X826000Y1094000D03*
Y1128000D03*
X844000Y1092000D03*
Y1128000D03*
X842700Y1071900D03*
X782712Y1211404D03*
Y1206904D03*
X772601Y1223511D03*
Y1219011D03*
Y1214511D03*
X777101Y1223511D03*
X832800Y1147500D03*
X795100Y1150400D03*
X798920Y1150500D03*
X821900Y1173700D03*
X773300Y1159700D03*
X769800Y1156500D03*
X776800Y1169700D03*
X780722Y1166357D03*
X780000Y1162800D03*
X859113Y1283983D03*
X822500Y1331000D03*
Y1298000D03*
Y1294000D03*
X860000Y1410843D03*
X842500Y1411343D03*
X852000Y1402000D03*
Y1406000D03*
X822500Y1373500D03*
Y1369500D03*
X835000Y1402500D03*
Y1398000D03*
X822500Y1335000D03*
X820000Y1448000D03*
X772361Y1451972D03*
X882823Y331182D03*
X909236Y333242D03*
X906486Y330524D03*
X910330Y363490D03*
X908340Y360430D03*
X909423Y354393D03*
X898059Y343029D03*
X902184Y347219D03*
X906616Y351586D03*
X922800Y362400D03*
X922700Y358100D03*
X945408Y378761D03*
X950843Y378827D03*
X871591Y431161D03*
X870400Y454315D03*
X867299Y493300D03*
Y497200D03*
X922525Y519833D03*
X873000Y494100D03*
X929096Y517567D03*
X873200Y487300D03*
X944387Y520100D03*
X941557Y547005D03*
X955000Y540800D03*
X935477Y524023D03*
X938338Y529107D03*
X938579Y551379D03*
X938623Y556600D03*
X956100Y516500D03*
X867299Y508600D03*
Y504700D03*
X935490Y519550D03*
X878740Y655190D03*
Y647190D03*
X884801Y630225D03*
X892400Y633700D03*
X878740Y643190D03*
Y651190D03*
X870200Y631500D03*
X867260Y608600D03*
X883030Y611940D03*
X878600Y615600D03*
X879600Y621600D03*
X878400Y626200D03*
X932986Y752682D03*
X874858Y757002D03*
X874706Y752583D03*
X905100Y777000D03*
X915580Y857420D03*
X942500Y797867D03*
X876255Y818998D03*
X880983Y804420D03*
X874500Y774500D03*
X936543Y762518D03*
X957500Y842400D03*
X944000D03*
X924484Y812558D03*
X921047Y811463D03*
X869989Y818847D03*
X931800Y791500D03*
X870001Y822862D03*
X934800Y795300D03*
X916855Y810934D03*
X909144Y803346D03*
X903700Y803200D03*
X912762Y792801D03*
X903221Y793938D03*
X912030Y787650D03*
X907800Y788700D03*
X913059Y810367D03*
X906166Y812784D03*
X902560Y813313D03*
X876862Y842155D03*
X881702Y838859D03*
X874593Y763800D03*
X874821Y767690D03*
X931380Y821500D03*
X935485Y821400D03*
X903572Y773740D03*
X931206Y845756D03*
X920170Y857430D03*
X903500Y769900D03*
X939500Y842400D03*
X924670Y857430D03*
X953000Y842400D03*
X911080Y857420D03*
X948500Y842400D03*
X881216Y813813D03*
X910807Y766589D03*
X904484Y786109D03*
X876256Y798895D03*
X874500Y779100D03*
X866655Y855100D03*
X870200Y852203D03*
X872600Y798700D03*
X943294Y838833D03*
X903300Y763200D03*
X879205Y873548D03*
X918369Y923258D03*
X914208Y924279D03*
X883072Y886211D03*
X889458Y907846D03*
X877877Y891277D03*
X940750Y886000D03*
X928250Y885250D03*
X934500Y885156D03*
X894317Y865406D03*
X890117D03*
X894317Y861206D03*
X890117D03*
X879667Y877303D03*
X884684Y877406D03*
X927260Y922470D03*
X909760Y925445D03*
X922760Y922470D03*
X958256Y894438D03*
X930310Y858550D03*
X879770Y868369D03*
X895500Y1038000D03*
X891600Y980000D03*
X888000D03*
X886400Y976500D03*
X893600D03*
X897200D03*
X895200Y980000D03*
X890000Y976500D03*
X944500Y1134500D03*
X952500D03*
X951500Y1117500D03*
X947000D03*
X943000D03*
X949500Y1114500D03*
X954500D03*
X956500Y1117500D03*
X948298Y1215500D03*
X943500Y1233000D03*
X951500D03*
X959500D03*
X957000Y1207500D03*
X953100Y1211400D03*
X953000Y1203600D03*
X904000Y1191700D03*
X877400D03*
X928500Y1220700D03*
X890500Y1201200D03*
X885930Y1210537D03*
X892460Y1211340D03*
X887200Y1216460D03*
X893200Y1203660D03*
X888825Y1208263D03*
X889965Y1213936D03*
X884677Y1219029D03*
X947700Y1185500D03*
X947500Y1233000D03*
X955500D03*
X926700Y1199000D03*
X952500Y1193300D03*
X884056Y1283981D03*
X871556D03*
X888000Y1424000D03*
X926000Y1420000D03*
X876500Y1410843D03*
X888776Y1402228D03*
X901435Y1402196D03*
X866500Y1392892D03*
X913935Y1402196D03*
X869937Y1400312D03*
X866000Y1398000D03*
X945415Y1429318D03*
X945414Y1412818D03*
X866000Y1452000D03*
X900000Y1450000D03*
X944019Y1452220D03*
X1033046Y379981D03*
X1035000Y370500D03*
X1032924Y374988D03*
X1038067Y441886D03*
X1021890Y439717D03*
X965700Y519617D03*
X962118Y534117D03*
X988341Y563811D03*
X968200Y547200D03*
X985631Y559671D03*
X984197Y533383D03*
X991538Y522018D03*
X1000051Y547644D03*
X974530Y559550D03*
X974550Y563690D03*
X1003591Y552081D03*
X996998Y539555D03*
X971420Y537950D03*
X975910Y537770D03*
X990200Y544250D03*
X995213Y529837D03*
X998905Y529824D03*
X986638Y519684D03*
X991360Y529780D03*
X963870Y754152D03*
X964200Y855600D03*
X1009600Y851054D03*
X986471Y829716D03*
X1009950Y838000D03*
X1025636Y854819D03*
X962000Y842400D03*
X966861Y772518D03*
X1050774Y815327D03*
X1050650Y825420D03*
X1022838Y829101D03*
X1042545Y832026D03*
X1015950Y838000D03*
X1026932Y841614D03*
X1050082Y843729D03*
X993400Y833250D03*
X969926Y847638D03*
X971197Y775799D03*
X977676Y828513D03*
X1005272Y837091D03*
X1000827Y837072D03*
X973070Y828512D03*
X1012125Y925875D03*
X1025251Y893000D03*
X1025065Y896965D03*
X1028500Y879500D03*
X1014807Y899075D03*
X1015007Y895000D03*
X997083Y895935D03*
X986728Y891100D03*
X974120Y858920D03*
X976242Y884600D03*
X980442Y882900D03*
X993942D03*
X1027524Y948954D03*
X1039500Y891100D03*
X1037110Y859471D03*
X989100Y899600D03*
X972042Y884600D03*
X985542Y882900D03*
X989742D03*
X996938Y901170D03*
X1034200Y945000D03*
X1040200D03*
X1046272Y944928D03*
X1039500Y874700D03*
X1024129Y946152D03*
X1044800Y893750D03*
X1030862Y951946D03*
X1022080Y960728D03*
X1032361Y1114039D03*
X1021970Y1096850D03*
X960500Y1134500D03*
X982500Y1136500D03*
X986500Y1131500D03*
X1013231Y1089300D03*
X1001687Y1111499D03*
X1008739Y1096000D03*
X961000Y1117500D03*
X1029500Y1104900D03*
X1028500Y1118601D03*
X1030178Y1134165D03*
X965500Y1128000D03*
X1012800Y1122100D03*
X1002671Y1124700D03*
X1029000Y1122400D03*
X977643Y1132490D03*
X1007431Y1122900D03*
X1020000Y1230000D03*
X971700Y1193100D03*
X963500Y1233000D03*
X967500D03*
X982500Y1217000D03*
Y1209000D03*
X960900Y1211400D03*
Y1203600D03*
X982500Y1144500D03*
X1026100Y1145996D03*
X1014500Y1153500D03*
X1012000Y1150000D03*
X1017500D03*
X1020000Y1153500D03*
X982500Y1201000D03*
Y1197000D03*
Y1213000D03*
Y1221000D03*
Y1225000D03*
Y1205000D03*
X964550Y1190200D03*
X1054918Y1330439D03*
Y1325739D03*
X1035943Y1424649D03*
X1031443Y1426899D03*
X1040127Y1422500D03*
X1033287Y1410500D03*
X1022818Y1393489D03*
X1024193Y1422899D03*
X1010943Y1413899D03*
X1005943Y1406700D03*
X975443Y1407700D03*
X992443Y1406700D03*
X1000443D03*
X988443D03*
X996443Y1406800D03*
X983943Y1407399D03*
X979443Y1406999D03*
X964810Y1421172D03*
X1037400Y1400600D03*
X1031400Y1399200D03*
X1054918Y1386039D03*
Y1353539D03*
Y1358239D03*
Y1381339D03*
X996693Y1421399D03*
X988693D03*
X1047000Y1421800D03*
X1039900Y1417000D03*
X1038303Y1441709D03*
X1021818Y1470865D03*
X1021693Y1444649D03*
X993100Y1456550D03*
X1007618Y1477365D03*
X1013418Y1470865D03*
X1027288Y1467441D03*
X1034100Y1500564D03*
X1024175Y1482189D03*
X1002118Y1471365D03*
X998325Y1471434D03*
X992443Y1441399D03*
X1002443D03*
X997443Y1436399D03*
Y1446399D03*
Y1441399D03*
X965443Y1436399D03*
X987576Y1451454D03*
Y1455054D03*
X982343Y1446620D03*
Y1440115D03*
X961877Y1445347D03*
Y1441451D03*
X999443Y1458006D03*
X1049260Y1466691D03*
X1017618Y1470865D03*
X993830Y1471364D03*
X1017618Y1460865D03*
X1043606Y1437906D03*
X962136Y1431831D03*
X1033253Y1444649D03*
X1048553Y1448399D03*
X1035526Y1455899D03*
X1041176Y1455500D03*
X1020500Y1500014D03*
X1037550Y1475814D03*
X1089000Y217500D03*
X1150000Y250000D03*
X1100000D03*
X1098000Y378000D03*
X1136000D03*
X1100000Y350000D03*
Y300000D03*
X1150000D03*
X1144000Y418000D03*
X1136100Y460288D03*
X1147440Y473040D03*
X1143720Y468520D03*
X1143420Y472900D03*
X1139590Y468380D03*
X1139330Y472820D03*
X1135410Y468380D03*
X1135310Y472820D03*
X1131800Y446800D03*
X1136000Y446849D03*
X1092000Y448400D03*
X1088000Y448500D03*
X1103100Y457300D03*
X1095100Y455800D03*
X1113593Y476094D03*
X1093000Y502000D03*
X1149964Y481623D03*
X1102677Y487116D03*
X1119242Y477261D03*
X1083000Y620000D03*
X1095000D03*
X1112298Y618498D03*
X1134600Y618747D03*
X1118505Y658863D03*
X1114905Y658882D03*
X1129500Y619200D03*
X1138900Y584900D03*
X1125025Y621993D03*
X1056116Y697100D03*
X1057826Y680233D03*
X1059927Y688329D03*
X1064216Y683751D03*
X1067554Y694447D03*
X1071179Y682315D03*
X1112682Y681223D03*
X1107674Y677776D03*
X1141230Y673825D03*
X1103770Y675413D03*
X1075706Y941261D03*
X1141370Y905550D03*
X1058800Y893750D03*
X1130000Y994000D03*
X1106000D03*
X1138000Y970000D03*
X1093588Y972000D03*
X1110600Y964200D03*
X1108500Y960600D03*
X1104600Y967800D03*
X1101950Y962900D03*
X1101600Y953700D03*
X1087962Y959252D03*
X1084000Y1092000D03*
X1130000Y1154000D03*
X1078000Y1166000D03*
X1080000Y1230000D03*
X1068569Y1191530D03*
X1072931Y1191482D03*
X1072900Y1204500D03*
X1084571Y1200129D03*
X1072600Y1211400D03*
X1084400Y1204200D03*
X1121346Y1315676D03*
Y1319676D03*
X1100625Y1292025D03*
X1107000Y1323500D03*
X1083100Y1305600D03*
X1082080Y1299375D03*
X1126820Y1288500D03*
X1075030Y1323078D03*
X1078850Y1287900D03*
X1082080Y1309495D03*
X1123000Y1297600D03*
X1096280Y1288150D03*
X1092475Y1287971D03*
X1133480Y1296700D03*
Y1291700D03*
X1121346Y1307385D03*
Y1311385D03*
X1117000Y1332500D03*
Y1328500D03*
X1072120Y1299375D03*
Y1304495D03*
Y1309495D03*
Y1292460D03*
X1114000Y1430000D03*
X1105100Y1351000D03*
Y1355000D03*
X1124612Y1388773D03*
X1130112Y1363273D03*
X1138112D03*
X1132112Y1380773D03*
X1114112Y1363273D03*
X1118112D03*
X1126112D03*
X1099112Y1387273D03*
Y1379273D03*
X1110512Y1403273D03*
X1067712Y1384766D03*
X1099112Y1391273D03*
X1099100Y1375200D03*
X1099112Y1383273D03*
X1099100Y1371200D03*
X1117362Y1406073D03*
X1134112Y1363273D03*
X1122112D03*
X1091000Y1393500D03*
X1086646Y1396419D03*
X1126112Y1401773D03*
X1130873Y1490848D03*
Y1495848D03*
X1238000Y164000D03*
X1236500Y216000D03*
X1200000Y250000D03*
X1218000Y344000D03*
X1225600Y368700D03*
X1200000Y300000D03*
X1190000Y466000D03*
X1184000Y440000D03*
X1206000Y430500D03*
X1160900Y468500D03*
X1245567Y420602D03*
X1243500Y393600D03*
X1201000Y447000D03*
X1200500Y452000D03*
X1169000Y511500D03*
X1150900Y485100D03*
X1177100Y495300D03*
X1167000Y586500D03*
X1232490Y664290D03*
X1236690D03*
X1171700Y603700D03*
X1172500Y599700D03*
X1169125Y581776D03*
X1166550Y579200D03*
X1188000Y753500D03*
X1212587Y740895D03*
Y736695D03*
Y732495D03*
X1232490Y668490D03*
X1212587Y728295D03*
X1236690Y668490D03*
X1212587Y724095D03*
X1232490Y672690D03*
X1212587Y719895D03*
X1236690Y672690D03*
X1206414Y704261D03*
X1209931Y701608D03*
X1207468Y697962D03*
X1210283Y695565D03*
X1212587Y749295D03*
Y745095D03*
X1232490Y685290D03*
X1179129Y672187D03*
X1232490Y681090D03*
X1180000Y832000D03*
Y848000D03*
X1217089Y846182D03*
X1224088Y844900D03*
X1213611Y831932D03*
X1228344Y852351D03*
X1190995Y776395D03*
X1186690Y791440D03*
X1217111Y825000D03*
X1173990Y797760D03*
X1177300Y804960D03*
X1180520Y790880D03*
X1179690Y798020D03*
X1200337Y912300D03*
X1200407Y918060D03*
X1157556Y932754D03*
X1184778Y912848D03*
X1180090Y896524D03*
X1181550Y906100D03*
X1184750Y889200D03*
Y896300D03*
X1240000Y1070000D03*
X1176000D03*
X1200000Y1100000D03*
X1155600Y1074500D03*
X1178000Y1214000D03*
X1200000Y1200000D03*
Y1150000D03*
X1223730Y1285803D03*
X1230600D03*
X1235600D03*
X1216894Y1318783D03*
Y1314783D03*
X1202394Y1285803D03*
X1197394D03*
X1190524D03*
X1183894Y1319783D03*
Y1315783D03*
X1193894Y1292533D03*
X1227100D03*
X1205624D03*
X1238830D03*
X1185324Y1286563D03*
X1220450Y1292533D03*
X1216894Y1304283D03*
Y1308283D03*
X1183894Y1304783D03*
Y1308783D03*
X1196000Y1366000D03*
X1212000D03*
X1242000Y1412000D03*
X1236600Y1346763D03*
X1232100D03*
X1217100D03*
X1183894D03*
X1203394D03*
X1198894D03*
X1178712Y1372573D03*
X1200962Y1413023D03*
X1209819Y1417377D03*
X1188894Y1346763D03*
X1222000Y1346700D03*
X1180614Y1340033D03*
X1213820D03*
X1243768Y1376953D03*
X1208394Y1346763D03*
X1193894D03*
X1227100D03*
X1203312Y1402793D03*
X1241600Y1346763D03*
X1169412Y1396873D03*
X1226000Y1436000D03*
X1238000Y1444000D03*
X1190000Y1494000D03*
X1156000D03*
X1200000Y1450000D03*
X1326000Y92000D03*
X1298655Y59926D03*
X1282106Y81319D03*
Y66319D03*
X1299800Y56000D03*
X1278038Y93821D03*
X1278698Y84340D03*
X1307200Y45000D03*
X1289106Y27697D03*
X1282106Y51319D03*
X1303500Y35000D03*
X1297000Y68500D03*
X1319100Y47400D03*
X1308000Y35000D03*
X1309500Y76500D03*
X1314500D03*
X1299500D03*
X1304500D03*
X1261100Y16600D03*
X1264700Y16400D03*
X1262000Y174000D03*
X1313000Y185500D03*
X1314000Y150500D03*
X1282106Y161319D03*
Y151319D03*
X1302500Y152000D03*
X1305000Y185500D03*
X1298500D03*
X1282106Y131319D03*
Y121319D03*
X1266600Y119500D03*
X1262468Y103268D03*
X1256800Y132400D03*
X1322500Y113500D03*
X1317500D03*
X1327000D03*
X1262600Y119700D03*
X1272500Y213000D03*
X1307500Y205000D03*
X1338000Y225000D03*
X1289106Y199941D03*
X1252000Y358000D03*
X1294500Y331500D03*
X1278500Y313000D03*
X1259445Y379019D03*
X1337824Y379176D03*
X1262945Y377600D03*
X1294624Y358802D03*
X1317500Y435500D03*
X1316000Y419000D03*
X1269926Y400687D03*
X1262964Y400469D03*
X1281693Y473218D03*
X1274396Y407915D03*
X1247949Y423302D03*
X1250648Y425686D03*
X1245959Y435527D03*
X1265295Y421223D03*
X1257000Y434600D03*
X1248500Y393600D03*
X1298500Y562500D03*
X1317500Y533500D03*
X1277606Y546575D03*
Y556024D03*
Y537126D03*
X1307500Y501500D03*
X1299900Y534200D03*
X1311200Y511500D03*
X1282106Y519075D03*
Y534075D03*
Y504075D03*
X1303800Y522500D03*
X1327000Y487000D03*
X1325500Y504750D03*
X1323000Y566500D03*
X1318000D03*
X1328000D03*
X1300100Y530000D03*
X1326500Y514000D03*
X1312000Y501500D03*
X1272182Y571361D03*
X1334500Y549500D03*
Y554500D03*
Y539500D03*
Y544500D03*
X1318000Y660000D03*
X1332000Y646000D03*
X1312973Y643128D03*
X1282106Y614075D03*
X1273979Y652690D03*
X1305000Y638500D03*
X1298000Y638300D03*
X1314000Y603500D03*
X1282106Y574075D03*
Y604075D03*
Y584075D03*
X1302500Y605000D03*
X1272211Y575575D03*
X1254000Y748000D03*
X1312000Y812000D03*
X1278000Y810000D03*
X1250000Y820000D03*
X1337824Y832935D03*
X1247588Y842190D03*
X1310000Y860000D03*
X1270000Y868000D03*
X1274000Y933209D03*
X1325500Y907000D03*
X1298000Y1014000D03*
X1318000Y986000D03*
X1266000Y1046000D03*
X1252000Y1010000D03*
X1266400Y1024700D03*
X1282106Y1036831D03*
Y1026831D03*
X1300600Y986800D03*
X1307500Y954000D03*
X1311200Y964000D03*
X1282106Y956831D03*
X1303800Y975000D03*
X1277606Y1008780D03*
Y999331D03*
Y989882D03*
X1282106Y986831D03*
Y971831D03*
X1325500Y957250D03*
X1323000Y1019000D03*
X1318000D03*
X1328000D03*
X1300900Y981800D03*
X1326500Y966500D03*
X1262400Y1024700D03*
X1312000Y954000D03*
X1260000Y993500D03*
X1334500Y1002000D03*
Y1007000D03*
Y992000D03*
Y997000D03*
X1266000Y1128000D03*
X1264000Y1082000D03*
X1250000Y1100000D03*
X1289106Y1105453D03*
X1314000Y1056000D03*
X1313000Y1091000D03*
X1298500D03*
X1302500Y1057500D03*
X1305000Y1091000D03*
X1282106Y1066831D03*
Y1056831D03*
X1250000Y1200000D03*
Y1150000D03*
X1288000Y1296000D03*
X1274000Y1314000D03*
X1300000Y1388000D03*
X1274000Y1374000D03*
X1318540Y1424331D03*
X1273874Y1423000D03*
X1314375Y1424375D03*
X1327900Y1416500D03*
X1266914Y1394873D03*
X1258187Y1389753D03*
X1281624Y1409209D03*
X1253165Y1384633D03*
X1246949Y1379513D03*
X1263642Y1392313D03*
X1261224Y1387193D03*
X1277624Y1409209D03*
X1250347Y1382073D03*
X1306625Y1434000D03*
X1303874Y1453750D03*
X1292374Y1452500D03*
X1301534Y1431345D03*
X1289124Y1430700D03*
X1253374Y1459300D03*
X1260874Y1481400D03*
X1264774Y1470700D03*
X1266574Y1452300D03*
X1289574Y1483700D03*
X1252674Y1496800D03*
X1266474Y1487500D03*
X1278574Y1488700D03*
X1282374Y1445500D03*
Y1464000D03*
X1296374Y1430700D03*
X1297089Y1450307D03*
X1322000Y1430700D03*
X1284624Y1476400D03*
X1253374Y1470000D03*
X1260574Y1445600D03*
X1256474Y1446000D03*
X1432000Y30000D03*
X1358000Y91000D03*
X1406319Y66319D03*
Y81319D03*
X1401819Y93819D03*
Y84370D03*
X1435200Y58500D03*
X1427800Y69500D03*
X1406319Y51319D03*
X1413319Y27697D03*
X1431500Y48500D03*
X1435750Y73750D03*
X1436000Y48500D03*
X1392500Y173000D03*
X1389000Y148500D03*
X1422000Y98000D03*
X1346000Y179000D03*
X1351500Y144500D03*
X1406319Y151319D03*
Y161319D03*
X1426500Y152000D03*
X1422500Y185500D03*
X1429000D03*
X1406319Y121319D03*
Y131319D03*
X1401819Y103268D03*
X1391200Y119500D03*
X1376700Y136000D03*
X1394200Y113700D03*
X1428000Y238000D03*
X1388500Y230000D03*
X1394000Y249000D03*
X1397937Y199951D03*
X1373000Y234500D03*
X1388000Y378000D03*
X1400000Y350000D03*
X1341324Y372244D03*
X1378000Y430000D03*
X1376000Y414000D03*
X1436500Y430000D03*
X1341343Y400626D03*
X1348305Y400844D03*
X1352557Y399595D03*
X1367514Y397100D03*
X1362514D03*
X1384000Y554000D03*
X1352000Y516000D03*
X1432000Y482000D03*
X1364000Y492000D03*
X1401819Y546575D03*
Y556024D03*
Y537126D03*
X1406319Y534075D03*
Y519075D03*
Y504075D03*
X1413319Y480453D03*
X1424400Y534200D03*
X1431500Y501500D03*
X1435200Y511500D03*
X1427800Y522500D03*
X1424500Y529100D03*
X1436000Y501500D03*
X1345215Y533601D03*
X1382000Y592000D03*
X1384000Y646000D03*
X1358000Y600000D03*
X1413319Y652697D03*
X1406319Y614075D03*
X1422500Y638500D03*
X1429000D03*
X1406319Y604075D03*
Y584075D03*
Y574075D03*
X1394110Y575530D03*
X1426500Y605000D03*
X1383952Y573102D03*
X1430000Y752000D03*
X1346000Y704000D03*
X1382000Y688000D03*
X1384000Y782000D03*
X1400000Y850000D03*
X1348305Y853600D03*
X1341343Y853382D03*
X1352557Y852351D03*
X1341324Y825000D03*
X1367500Y851922D03*
X1362500D03*
X1413319Y933209D03*
X1342000Y976000D03*
X1356000Y998000D03*
X1424100Y987000D03*
X1391000Y1024800D03*
X1406319Y1036831D03*
Y1026831D03*
Y956831D03*
X1431500Y954000D03*
X1435200Y964000D03*
X1427800Y975000D03*
X1401819Y1008780D03*
Y999331D03*
Y989882D03*
X1406319Y986831D03*
Y971831D03*
X1424400Y982000D03*
X1386900Y1024600D03*
X1383200Y992700D03*
X1436000Y954000D03*
X1360000Y1054000D03*
X1350000Y1100000D03*
X1413319Y1105453D03*
X1426500Y1057500D03*
X1422500Y1091000D03*
X1429000D03*
X1406319Y1066831D03*
Y1056831D03*
X1350000Y1150000D03*
X1400000D03*
Y1200000D03*
X1350000D03*
X1366000Y1388000D03*
X1347400Y1416200D03*
X1406000Y1444000D03*
X1474000Y78000D03*
X1508000Y36000D03*
X1468000Y42000D03*
X1482000Y66000D03*
X1530531Y66319D03*
Y81319D03*
X1526031Y93819D03*
Y84370D03*
X1439500Y81000D03*
X1530531Y51319D03*
X1450500Y61000D03*
X1458500Y86500D03*
Y91500D03*
X1508500Y102500D03*
X1441100Y130800D03*
X1494000Y98000D03*
X1484000Y158000D03*
X1530531Y151319D03*
X1526823Y161308D03*
X1437000Y185500D03*
X1438000Y150500D03*
X1530531Y121319D03*
Y131319D03*
X1526031Y103268D03*
X1515400Y119400D03*
X1501300Y136100D03*
X1447000Y113500D03*
X1442000D03*
X1452000D03*
X1511400Y119500D03*
X1458500Y96500D03*
Y101500D03*
X1523100Y193700D03*
X1502000Y196000D03*
X1457500Y289000D03*
X1508500Y292500D03*
X1450000Y350000D03*
X1462036Y379176D03*
X1465536Y372244D03*
X1484000Y432000D03*
X1476769Y399595D03*
X1465555Y400626D03*
X1472517Y400844D03*
X1492014Y397100D03*
X1487014D03*
X1442500Y532000D03*
X1480000Y546000D03*
X1510000Y488000D03*
X1476000Y518000D03*
X1526031Y546575D03*
Y556024D03*
Y537126D03*
X1530531Y534075D03*
Y519075D03*
Y504075D03*
X1449500Y504750D03*
X1447000Y566500D03*
X1442000D03*
X1452000D03*
X1450500Y514000D03*
X1458500Y544500D03*
Y539500D03*
Y554500D03*
Y549500D03*
X1451800Y583800D03*
X1498000Y586000D03*
X1490000Y598000D03*
X1500000Y640000D03*
X1460000Y646000D03*
X1530531Y614075D03*
X1437000Y638500D03*
X1530531Y604075D03*
Y584075D03*
Y574075D03*
X1515200Y572200D03*
X1438000Y603500D03*
X1511200Y572300D03*
X1508000Y748000D03*
X1472517Y853600D03*
X1465555Y853382D03*
X1462036Y831932D03*
X1476769Y852351D03*
X1465536Y825000D03*
X1493500Y853100D03*
X1487000Y851600D03*
X1443992Y904962D03*
X1442500Y984500D03*
X1478000Y976000D03*
X1480000Y1020000D03*
X1515400Y1025000D03*
X1530531Y1036831D03*
Y1026831D03*
Y956831D03*
X1526031Y1008780D03*
Y999331D03*
Y989882D03*
X1530531Y986831D03*
Y971831D03*
X1450100Y959500D03*
X1447000Y1019000D03*
X1442000D03*
X1452000D03*
X1450500Y966500D03*
X1511400Y1024600D03*
X1506000Y993000D03*
X1458500Y1002000D03*
Y1007000D03*
Y992000D03*
Y997000D03*
X1500000Y1100000D03*
X1530531Y1066831D03*
Y1056831D03*
X1437000Y1091000D03*
X1438000Y1056000D03*
X1450000Y1150000D03*
X1500000D03*
Y1200000D03*
X1450000D03*
X1500000Y1300000D03*
X1450000D03*
Y1350000D03*
X1500000D03*
Y1450000D03*
X1450000D03*
X1594000Y56000D03*
X1574000Y26000D03*
X1608000Y62000D03*
Y50000D03*
X1549300Y56000D03*
X1548500Y62900D03*
X1553000Y35000D03*
X1556700Y45000D03*
X1537531Y27697D03*
X1548279Y69309D03*
X1575400Y50750D03*
X1557500Y35000D03*
X1549000Y76500D03*
X1554000D03*
X1564000D03*
X1559000D03*
X1593500Y160500D03*
X1546000Y112000D03*
X1547000Y156222D03*
Y185500D03*
X1562500Y150500D03*
X1561500Y185500D03*
X1553500Y189500D03*
X1625300Y136000D03*
X1596400Y135600D03*
Y131100D03*
Y126100D03*
X1598000Y206000D03*
X1568000Y204000D03*
X1592000Y236000D03*
X1616100Y203786D03*
X1550000Y350000D03*
X1586249Y379176D03*
X1589749Y372244D03*
X1553500Y431500D03*
X1604000Y432500D03*
X1600982Y399595D03*
X1596730Y400844D03*
X1589768Y400626D03*
X1611014Y397100D03*
X1616014D03*
X1566500Y533000D03*
X1604000Y536000D03*
X1594000Y506000D03*
X1558000Y482000D03*
X1559700Y511500D03*
X1556000Y501500D03*
X1548600Y534900D03*
X1552300Y522500D03*
X1537531Y480453D03*
X1574000Y504750D03*
X1571500Y566500D03*
X1566500D03*
X1576500D03*
X1548400Y528800D03*
X1575000Y514000D03*
X1560500Y501500D03*
X1583000Y544500D03*
Y539500D03*
Y554500D03*
Y549500D03*
X1570100Y583800D03*
X1568000Y660000D03*
X1584000Y648000D03*
X1553500Y638500D03*
X1561500Y639860D03*
X1537500Y656000D03*
X1551000Y605000D03*
X1562500Y603500D03*
X1602000Y684000D03*
X1566000Y772000D03*
X1550000Y850000D03*
X1596730Y853600D03*
X1589768Y853382D03*
X1586249Y831932D03*
X1597000Y857500D03*
X1591400Y825000D03*
X1616000Y850100D03*
X1611000D03*
X1599000Y941000D03*
X1579000Y940000D03*
X1564000Y876000D03*
X1537531Y933209D03*
X1572900Y902900D03*
X1604000Y1022000D03*
X1544000Y1004500D03*
X1566500Y985500D03*
X1600500Y975000D03*
X1612000Y980000D03*
X1548900Y987600D03*
X1556000Y954000D03*
X1559700Y964000D03*
X1552300Y975000D03*
X1574000Y957250D03*
X1571500Y1019000D03*
X1566500D03*
X1576500D03*
X1575000Y966500D03*
X1548900Y981500D03*
X1560500Y954000D03*
X1583000Y997000D03*
Y992000D03*
Y1007000D03*
Y1002000D03*
X1561500Y1091000D03*
X1553500D03*
X1600000Y1100000D03*
X1537531Y1105453D03*
X1551000Y1057500D03*
X1547000Y1091000D03*
X1562500Y1056000D03*
X1600000Y1200000D03*
Y1150000D03*
X1550000Y1300000D03*
X1600000D03*
X1550000Y1350000D03*
X1600000D03*
Y1450000D03*
X1550000D03*
X1718000Y66000D03*
X1680000Y26000D03*
X1632000D03*
X1676300Y69500D03*
X1683700Y58500D03*
X1686730Y80991D03*
X1654744Y66319D03*
Y81319D03*
X1650244Y93819D03*
Y84370D03*
X1680000Y48500D03*
X1654744Y51319D03*
X1661744Y27697D03*
X1699000Y61000D03*
X1672900Y76400D03*
X1684500Y48500D03*
X1692200Y86200D03*
Y91200D03*
X1636000Y176000D03*
X1677500Y185500D03*
X1686500Y150500D03*
X1675000Y152000D03*
X1654744Y151319D03*
Y161319D03*
X1685500Y185500D03*
X1654744Y121319D03*
X1653206Y134559D03*
X1650244Y103268D03*
X1639300Y119500D03*
X1690400Y114100D03*
X1695400D03*
X1700400D03*
X1635300Y119600D03*
X1692300Y96100D03*
X1707000Y103500D03*
X1648000Y212000D03*
X1682000Y206000D03*
X1661744Y199941D03*
X1671003Y190635D03*
X1712525Y191268D03*
X1650000Y380000D03*
X1638500Y311500D03*
X1715000Y305500D03*
X1648000Y468000D03*
X1714000Y391000D03*
X1721762Y458436D03*
Y454436D03*
X1696359Y452707D03*
X1689359D03*
X1691859Y460207D03*
X1687359Y457207D03*
X1681859Y452707D03*
X1709496Y463382D03*
X1717859Y463907D03*
X1714026Y464191D03*
X1711199Y453177D03*
X1708359Y449207D03*
X1706859Y445207D03*
X1682000Y484000D03*
X1720000Y506000D03*
X1650244Y546575D03*
Y556024D03*
Y537126D03*
X1654744Y534075D03*
Y519075D03*
Y504075D03*
X1661744Y480453D03*
X1680000Y501500D03*
X1673200Y535100D03*
X1683700Y511500D03*
X1676300Y522500D03*
X1698000Y504750D03*
X1695500Y566500D03*
X1690500D03*
X1700500D03*
X1673200Y529000D03*
X1699000Y514000D03*
X1684500Y501500D03*
X1707083Y543435D03*
Y538435D03*
X1706800Y556300D03*
X1706935Y548158D03*
X1706000Y646000D03*
X1632000Y648000D03*
X1634000Y618000D03*
X1661744Y652697D03*
X1654744Y614075D03*
X1671000Y638500D03*
X1685500D03*
X1677500D03*
X1654744Y604075D03*
Y584075D03*
X1652808Y574040D03*
X1686500Y603500D03*
X1675000Y605000D03*
X1638200Y572200D03*
X1634200D03*
X1700000Y700000D03*
X1650000D03*
Y750000D03*
X1700000D03*
X1650000Y850000D03*
X1720942Y853600D03*
X1713980Y853382D03*
X1710461Y831932D03*
X1713961Y825000D03*
X1690200Y937700D03*
X1718000Y938000D03*
X1716000Y878000D03*
X1661800Y933400D03*
X1709500Y900700D03*
X1668000Y1004000D03*
X1690500Y986000D03*
X1672800Y987300D03*
X1639100Y1024900D03*
X1654744Y1036831D03*
Y1026831D03*
Y956831D03*
X1676300Y975000D03*
X1683700Y964000D03*
X1680000Y954000D03*
X1650244Y1008780D03*
Y999331D03*
Y989882D03*
X1654744Y986831D03*
Y971831D03*
X1698000Y957250D03*
X1695500Y1019000D03*
X1690500D03*
X1700500D03*
X1699000Y966500D03*
X1672800Y981200D03*
X1635100Y1024700D03*
X1631500Y994000D03*
X1684500Y954000D03*
X1707000Y997000D03*
Y992000D03*
Y1007000D03*
Y1002000D03*
X1638000Y1082000D03*
X1696000Y1106000D03*
X1661744Y1105453D03*
X1677500Y1091000D03*
X1686500Y1056000D03*
X1671000Y1091000D03*
X1675000Y1057500D03*
X1685500Y1091000D03*
X1654744Y1066831D03*
Y1056831D03*
X1650000Y1150000D03*
X1700000D03*
Y1200000D03*
X1650000D03*
Y1300000D03*
X1676511Y1292495D03*
X1674000Y1410000D03*
X1650000Y1350000D03*
X1669376Y1429200D03*
X1651906Y1428973D03*
X1719726Y1402700D03*
X1716026Y1416500D03*
X1663906Y1428973D03*
X1659906D03*
X1694751Y1434000D03*
X1683926Y1453750D03*
X1672626Y1452500D03*
X1686226Y1432500D03*
X1656250Y1461250D03*
X1662626Y1464000D03*
Y1445500D03*
X1674926Y1447400D03*
X1676626Y1432000D03*
X1702501Y1434000D03*
X1661626Y1480000D03*
X1756000Y25500D03*
X1730000Y58000D03*
X1811700Y59550D03*
X1808600Y78200D03*
X1803500Y82200D03*
X1778956Y66319D03*
Y81319D03*
X1774456Y93819D03*
Y84370D03*
X1785956Y27697D03*
X1778956Y51319D03*
X1795600Y44900D03*
X1817500Y32700D03*
X1814850Y21500D03*
X1799094Y82033D03*
X1811600Y32800D03*
X1794300Y63400D03*
X1796300Y85600D03*
X1806300D03*
X1811300D03*
X1801300D03*
X1803620Y57000D03*
X1807500Y57400D03*
X1730500Y177500D03*
X1730000Y136000D03*
X1746000Y106000D03*
X1809500Y185500D03*
X1801500D03*
X1811305Y147994D03*
X1799000Y152000D03*
X1795000Y185500D03*
X1778956Y151319D03*
Y161319D03*
Y121319D03*
Y131319D03*
X1774456Y103268D03*
X1763600Y119400D03*
X1749700Y135600D03*
X1759600Y119500D03*
X1804000Y205000D03*
X1724000Y232000D03*
X1754000Y234000D03*
X1750000Y200000D03*
X1785956Y199941D03*
X1768000Y310000D03*
X1781500Y366000D03*
X1801642Y379532D03*
X1805142Y372600D03*
X1724000Y422000D03*
X1745737Y400643D03*
X1800436Y412804D03*
X1804436D03*
X1809633Y420927D03*
Y416927D03*
X1795433D03*
Y420927D03*
X1759904Y400647D03*
X1812123Y401200D03*
X1805142Y400982D03*
X1814359Y473207D03*
X1725596Y447182D03*
X1729596Y443182D03*
X1725596D03*
X1729596Y455182D03*
X1725596D03*
X1729596Y459182D03*
X1725596D03*
Y451182D03*
X1729596Y447182D03*
Y451182D03*
X1731710Y475473D03*
X1749952Y405830D03*
X1764168Y405501D03*
X1816375Y399951D03*
X1723896Y474582D03*
X1753631Y405830D03*
X1735014Y397100D03*
X1740014D03*
X1755159Y469723D03*
X1740906Y465239D03*
X1746859Y465707D03*
X1724096Y464344D03*
X1746959Y459107D03*
X1742758Y456059D03*
X1813700Y548300D03*
X1796000Y566500D03*
X1728000Y554000D03*
X1757200Y558900D03*
X1730000Y568000D03*
X1809559Y482507D03*
Y486507D03*
X1795359D03*
Y482507D03*
X1800556Y490630D03*
X1804556D03*
X1774456Y556024D03*
X1767342Y533721D03*
X1774456Y546575D03*
X1785956Y480453D03*
X1804000Y501500D03*
X1807700Y511500D03*
X1800300Y522500D03*
X1798100Y537973D03*
X1785728Y538736D03*
X1778956Y519075D03*
Y504075D03*
X1814500Y566500D03*
X1797400Y528800D03*
X1742859Y484707D03*
X1808500Y501500D03*
X1818000Y656000D03*
X1762000Y628000D03*
X1756000Y646000D03*
X1785956Y652697D03*
X1795000Y638500D03*
X1801500D03*
X1809500D03*
X1778956Y614075D03*
X1810500Y603500D03*
X1799000Y605000D03*
X1778956Y604075D03*
Y584075D03*
Y574075D03*
X1759750Y576000D03*
Y587000D03*
X1758000Y748000D03*
X1756000Y684000D03*
X1808000Y848000D03*
X1760000Y846000D03*
X1800000Y800000D03*
X1725194Y852351D03*
X1740000Y850100D03*
X1735000D03*
X1778500Y917500D03*
X1738000Y904000D03*
X1796166Y892754D03*
Y888754D03*
X1785956Y933209D03*
X1804000Y885500D03*
Y881500D03*
X1800000Y885500D03*
Y893500D03*
X1804000D03*
X1800000Y889500D03*
X1804000D03*
X1800000Y877500D03*
X1804000D03*
X1800000Y881500D03*
X1806114Y909791D03*
X1770763Y887025D03*
X1763763D03*
X1766263Y894525D03*
X1761763Y891525D03*
X1756263Y887025D03*
X1798300Y908900D03*
X1817263Y919025D03*
X1815310Y899557D03*
X1783900Y897700D03*
X1792263Y898225D03*
X1798500Y898662D03*
X1788430Y898509D03*
X1817739Y889758D03*
X1785603Y887495D03*
X1782763Y883525D03*
X1781263Y879525D03*
X1794500Y1007000D03*
X1814500Y985500D03*
X1724000Y974000D03*
X1728000Y1002000D03*
X1796900Y987200D03*
X1763300Y1024800D03*
X1778956Y1036831D03*
Y1026831D03*
X1800300Y975000D03*
X1804000Y954000D03*
X1807700Y964000D03*
X1778956Y956831D03*
X1774456Y1008780D03*
Y999331D03*
Y989882D03*
X1778956Y986831D03*
Y971831D03*
X1814500Y1019000D03*
X1796900Y981100D03*
X1759300Y1024900D03*
X1808500Y954000D03*
X1756000Y993500D03*
X1730000Y1050000D03*
X1762000Y1080000D03*
X1785956Y1105453D03*
X1809500Y1091000D03*
X1801500D03*
X1810500Y1056000D03*
X1795000Y1091000D03*
X1799000Y1057500D03*
X1778956Y1066831D03*
Y1056831D03*
X1750000Y1150000D03*
Y1200000D03*
X1800000Y1300000D03*
Y1250000D03*
X1760000Y1394000D03*
X1800000Y1350000D03*
X1735126Y1416300D03*
X1790226Y1458600D03*
X1803426Y1452600D03*
X1804326Y1480500D03*
X1794226Y1473300D03*
X1810426Y1476200D03*
X1790226Y1469300D03*
X1800326Y1445800D03*
X1794426Y1446400D03*
X1820200Y70140D03*
X1898669Y93819D03*
Y84370D03*
X1903169Y66319D03*
Y81319D03*
X1885200Y81000D03*
X1871400Y82000D03*
X1903169Y51319D03*
X1910169Y27697D03*
X1887900Y41300D03*
X1878000Y29300D03*
X1884600Y49000D03*
X1821850Y35400D03*
X1824200Y23400D03*
Y19000D03*
X1868600Y68922D03*
X1872900Y49000D03*
X1870607Y75897D03*
X1823300Y88600D03*
X1845900Y77300D03*
X1840900D03*
X1850800Y77200D03*
X1860500Y38100D03*
X1863950Y45400D03*
X1859050Y19000D03*
X1885508Y77413D03*
X1891300Y49400D03*
X1880500Y48900D03*
X1842400Y29500D03*
X1875500Y87000D03*
X1880500D03*
X1865500D03*
X1870500D03*
X1851500Y171500D03*
X1867600Y104300D03*
X1903169Y151319D03*
Y161319D03*
X1881000Y162200D03*
X1883000Y181500D03*
X1841000Y140000D03*
X1903169Y121319D03*
Y131319D03*
X1898669Y103268D03*
X1860817Y120141D03*
X1864800Y132500D03*
X1834018Y169783D03*
X1823500Y113500D03*
X1819134Y109132D03*
X1819000Y113500D03*
X1840500Y237500D03*
X1850000Y200000D03*
X1900000Y250000D03*
X1910169Y199941D03*
X1829500Y311000D03*
X1900000Y300000D03*
Y350000D03*
X1830000Y424000D03*
X1838000Y415500D03*
X1850000Y400000D03*
X1900000D03*
Y450000D03*
X1818359Y473207D03*
X1822359D03*
X1826359D03*
X1830359D03*
X1834359D03*
X1827114Y397900D03*
X1832114D03*
X1836476Y467034D03*
X1884000Y488000D03*
X1854000Y482000D03*
X1875000Y558000D03*
X1898669Y546575D03*
Y556024D03*
Y537126D03*
X1883200Y534600D03*
X1855750Y551000D03*
X1903169Y534075D03*
Y519075D03*
Y504075D03*
X1910169Y480453D03*
X1866700Y512800D03*
X1866500Y507250D03*
X1859300Y524500D03*
X1822000Y504750D03*
X1848500Y504000D03*
X1819500Y566500D03*
X1824500D03*
X1855750Y540000D03*
X1839750Y530250D03*
X1841500Y558000D03*
X1846000D03*
X1850500D03*
X1823000Y514000D03*
X1883300Y530000D03*
X1853000Y504000D03*
X1870500Y540500D03*
X1865500D03*
X1880500D03*
X1875500D03*
X1831000Y544500D03*
Y539500D03*
Y554500D03*
Y549500D03*
X1851400Y623800D03*
X1850000Y650000D03*
X1910169Y652697D03*
X1903169Y614075D03*
X1880500Y615200D03*
X1887000Y638500D03*
X1903169Y604075D03*
Y584075D03*
Y574075D03*
X1865000Y573000D03*
X1864700Y585500D03*
X1841000Y593000D03*
X1846000Y686000D03*
X1900000Y750000D03*
Y700000D03*
Y800000D03*
X1874540Y847322D03*
X1878540D03*
X1883737Y855445D03*
Y851445D03*
X1869537D03*
Y855445D03*
X1849407Y852351D03*
X1845155Y853600D03*
X1838193Y853382D03*
X1834674Y831932D03*
X1838174Y825000D03*
X1859500Y850100D03*
X1864500D03*
X1883663Y917025D03*
Y921025D03*
X1874660Y925148D03*
X1878660D03*
X1869463Y921025D03*
Y917025D03*
X1910169Y933209D03*
X1888763Y907525D03*
X1892763D03*
X1896763D03*
X1900763D03*
X1904763D03*
X1908763D03*
X1820700Y940600D03*
X1848500Y940200D03*
X1829563Y904041D03*
X1828763Y865025D03*
X1821263Y900025D03*
X1821363Y893425D03*
X1872500Y1010500D03*
X1826000Y1036500D03*
X1864500Y1038500D03*
X1865000Y1026000D03*
X1903169Y1036831D03*
Y1026831D03*
X1841000Y1046000D03*
X1903169Y956831D03*
X1859600Y960250D03*
X1883100Y984750D03*
X1870800Y973100D03*
X1898669Y1008780D03*
Y999331D03*
Y989882D03*
X1903169Y986831D03*
Y971831D03*
X1855750Y1004000D03*
X1859300Y977500D03*
X1822000Y957250D03*
X1848500Y957000D03*
X1850500Y1011000D03*
X1846000D03*
X1841500D03*
X1819500Y1019000D03*
X1824500D03*
X1855750Y993000D03*
X1823000Y966500D03*
X1839750Y983000D03*
X1875800Y981000D03*
X1853000Y957000D03*
X1865500Y993000D03*
X1881814Y993136D03*
X1876814D03*
X1871814D03*
X1831000Y1002000D03*
Y1007000D03*
Y992000D03*
Y997000D03*
X1827600Y970700D03*
X1850000Y1078000D03*
X1910169Y1105453D03*
X1887000Y1091500D03*
X1880500Y1068200D03*
X1903169Y1066831D03*
Y1056831D03*
X1850000Y1200000D03*
X1900000D03*
Y1150000D03*
X1850000D03*
X1900000Y1300000D03*
X1850000D03*
X1900000Y1250000D03*
X1850000D03*
X1900000Y1400000D03*
X1850000D03*
Y1350000D03*
X1900000D03*
X1904000Y1504000D03*
X1878000Y1484000D03*
X1822000Y1444000D03*
X1900000Y1450000D03*
X1824826Y1470900D03*
X1822326Y1481600D03*
X1919000Y51000D03*
X1922400Y470400D03*
X1923600Y913525D03*
X1914500Y902000D03*
X1918800Y1112100D03*
G54D40*
X104226Y904041D03*
X202053Y466305D03*
X1744822Y469723D03*
X1819226Y904041D03*
G54D31*
X75357Y895343D03*
Y893374D03*
Y891406D03*
Y889437D03*
Y887469D03*
Y885500D03*
Y883531D03*
Y881563D03*
Y879594D03*
Y877626D03*
Y875657D03*
X94643D03*
Y877626D03*
Y879594D03*
Y881563D03*
Y883531D03*
Y885500D03*
Y887469D03*
Y889437D03*
Y891406D03*
Y893374D03*
Y895343D03*
X173184Y457607D03*
Y455638D03*
Y453670D03*
Y451701D03*
Y449733D03*
Y447764D03*
Y445795D03*
Y443827D03*
Y441858D03*
Y439890D03*
Y437921D03*
X192470D03*
Y439890D03*
Y441858D03*
Y443827D03*
Y445795D03*
Y447764D03*
Y449733D03*
Y451701D03*
Y453670D03*
Y455638D03*
Y457607D03*
X1715953Y461025D03*
Y459056D03*
Y457088D03*
Y455119D03*
Y453151D03*
Y451182D03*
Y449213D03*
Y447245D03*
Y445276D03*
Y443308D03*
Y441339D03*
X1735239D03*
Y443308D03*
Y445276D03*
Y447245D03*
Y449213D03*
Y451182D03*
Y453151D03*
Y455119D03*
Y457088D03*
Y459056D03*
Y461025D03*
X1790357Y895343D03*
Y893374D03*
Y891406D03*
Y889437D03*
Y887469D03*
Y885500D03*
Y883531D03*
Y881563D03*
Y879594D03*
Y877626D03*
Y875657D03*
X1809643D03*
Y877626D03*
Y879594D03*
Y881563D03*
Y883531D03*
Y885500D03*
Y887469D03*
Y889437D03*
Y891406D03*
Y893374D03*
Y895343D03*
G54D22*
X65563Y887525D03*
X163390Y449789D03*
X1027363Y1114199D03*
X1002300Y1099000D03*
X984300Y1126800D03*
X1706159Y453207D03*
X1780563Y887525D03*
G54D13*
X100412Y6000D03*
X95412D03*
X90412D03*
X85412D03*
X80412D03*
X75412D03*
X70412D03*
X65412D03*
X60412D03*
X55412D03*
X50412D03*
X45412D03*
X40412D03*
X35412D03*
X30412D03*
X25412D03*
X20412D03*
X15412D03*
X10412D03*
X6000Y6588D03*
Y11588D03*
Y16588D03*
Y21588D03*
Y26588D03*
Y31588D03*
Y36588D03*
Y41588D03*
Y46588D03*
Y51588D03*
Y56588D03*
Y61588D03*
Y66588D03*
Y71588D03*
Y76588D03*
Y81588D03*
Y86588D03*
Y91588D03*
Y96588D03*
Y101588D03*
Y106588D03*
Y111588D03*
Y116588D03*
Y121588D03*
Y126588D03*
Y131588D03*
Y136588D03*
Y141588D03*
Y146588D03*
Y151588D03*
Y156588D03*
Y161588D03*
Y166588D03*
Y171588D03*
Y176588D03*
Y181588D03*
Y186588D03*
Y191588D03*
Y196588D03*
Y201588D03*
Y206588D03*
Y211588D03*
Y216588D03*
Y221588D03*
Y226588D03*
Y231588D03*
Y236588D03*
Y241588D03*
Y246588D03*
Y251588D03*
Y256588D03*
Y261588D03*
Y266588D03*
Y271588D03*
Y276588D03*
Y281588D03*
Y286588D03*
Y291588D03*
Y296588D03*
Y301588D03*
Y306588D03*
Y311588D03*
Y316588D03*
Y321588D03*
Y326588D03*
Y331588D03*
Y336588D03*
Y341588D03*
Y346588D03*
Y351588D03*
Y356588D03*
Y361588D03*
Y366588D03*
Y371588D03*
Y376588D03*
Y441588D03*
Y436588D03*
Y431588D03*
Y426588D03*
Y421588D03*
Y416588D03*
Y411588D03*
Y406588D03*
Y386588D03*
Y391588D03*
Y396588D03*
Y401588D03*
Y446588D03*
Y451588D03*
Y456588D03*
Y461588D03*
Y381588D03*
Y466588D03*
Y471588D03*
Y476588D03*
Y481588D03*
Y486588D03*
Y491588D03*
Y496588D03*
Y501588D03*
Y506588D03*
Y511588D03*
Y516588D03*
Y521588D03*
Y526588D03*
Y531588D03*
Y536588D03*
Y541588D03*
Y546588D03*
Y551588D03*
Y556588D03*
Y561588D03*
Y566588D03*
Y571588D03*
Y576588D03*
Y581588D03*
Y586588D03*
Y591588D03*
Y596588D03*
Y601588D03*
Y606588D03*
Y611588D03*
Y616588D03*
Y621588D03*
Y626588D03*
Y631588D03*
Y636588D03*
Y641588D03*
Y646588D03*
Y651588D03*
Y656588D03*
Y661588D03*
Y666588D03*
Y671588D03*
Y676588D03*
Y681588D03*
Y686588D03*
Y691588D03*
Y696588D03*
Y701588D03*
Y706588D03*
Y711588D03*
Y716588D03*
Y721588D03*
Y726588D03*
Y731588D03*
Y736588D03*
Y741588D03*
Y746588D03*
Y751588D03*
Y756588D03*
Y761588D03*
Y766588D03*
Y771588D03*
Y776588D03*
Y781588D03*
Y786588D03*
Y791588D03*
Y796588D03*
Y801588D03*
Y806588D03*
Y811588D03*
Y816588D03*
Y821588D03*
Y826588D03*
Y831588D03*
Y836588D03*
Y841588D03*
Y846588D03*
Y851588D03*
Y856588D03*
Y861588D03*
Y866588D03*
Y871588D03*
Y876588D03*
Y881588D03*
Y886588D03*
Y891588D03*
Y896588D03*
Y901588D03*
Y906588D03*
Y911588D03*
Y916588D03*
Y921588D03*
Y926588D03*
Y931588D03*
Y936588D03*
Y941588D03*
Y946588D03*
Y951588D03*
X26300Y873700D03*
Y864100D03*
Y868900D03*
X21500Y873700D03*
Y864100D03*
Y868900D03*
X6000Y956588D03*
Y961588D03*
Y966588D03*
Y971588D03*
Y976588D03*
Y981588D03*
Y986588D03*
Y991588D03*
Y996588D03*
Y1001588D03*
Y1006588D03*
Y1011588D03*
Y1016588D03*
Y1021588D03*
Y1026588D03*
Y1031588D03*
Y1036588D03*
Y1041588D03*
Y1046588D03*
Y1051588D03*
Y1056588D03*
Y1061588D03*
Y1066588D03*
Y1071588D03*
Y1076588D03*
Y1081588D03*
Y1086588D03*
Y1091588D03*
Y1096588D03*
Y1101588D03*
Y1106588D03*
Y1111588D03*
Y1116588D03*
Y1121588D03*
Y1126588D03*
Y1131588D03*
Y1136588D03*
Y1141588D03*
Y1146588D03*
Y1151588D03*
Y1156588D03*
Y1161588D03*
Y1166588D03*
Y1171588D03*
Y1176588D03*
Y1181588D03*
Y1186588D03*
Y1191588D03*
Y1196588D03*
Y1201588D03*
Y1206588D03*
Y1211588D03*
Y1216588D03*
Y1221588D03*
Y1226588D03*
Y1231588D03*
Y1236588D03*
Y1321588D03*
Y1326588D03*
Y1331588D03*
Y1286588D03*
Y1291588D03*
Y1296588D03*
Y1301588D03*
Y1306588D03*
Y1311588D03*
Y1316588D03*
Y1241588D03*
Y1246588D03*
Y1251588D03*
Y1256588D03*
Y1261588D03*
Y1266588D03*
Y1271588D03*
Y1276588D03*
Y1281588D03*
Y1421588D03*
Y1416588D03*
Y1411588D03*
Y1406588D03*
Y1401588D03*
Y1396588D03*
Y1391588D03*
Y1386588D03*
Y1381588D03*
Y1376588D03*
Y1371588D03*
Y1366588D03*
Y1361588D03*
Y1356588D03*
Y1351588D03*
Y1346588D03*
Y1341588D03*
Y1426588D03*
Y1336588D03*
Y1451588D03*
Y1446588D03*
Y1441588D03*
Y1436588D03*
Y1431588D03*
X99000Y1501000D03*
X61500Y1502000D03*
X87539Y1499118D03*
X82539D03*
X77539D03*
X72539D03*
X67539D03*
X92539D03*
X11000Y1455500D03*
X15500Y1458500D03*
X17811Y1462693D03*
Y1467693D03*
Y1472693D03*
Y1477693D03*
Y1482693D03*
Y1487693D03*
Y1492693D03*
Y1497693D03*
Y1502693D03*
Y1507693D03*
X17500Y1512000D03*
X21819Y1513685D03*
X26819D03*
X31819D03*
X36819D03*
X41819D03*
X46819D03*
X51819D03*
X56819D03*
X58500Y1508000D03*
X195412Y6000D03*
X190412D03*
X185412D03*
X180412D03*
X175412D03*
X170412D03*
X165412D03*
X160412D03*
X155412D03*
X150412D03*
X145412D03*
X140412D03*
X135412D03*
X130412D03*
X125412D03*
X120412D03*
X115412D03*
X110412D03*
X105412D03*
X127600Y437500D03*
Y432700D03*
X122800Y437500D03*
Y432700D03*
X127600Y427900D03*
X122800D03*
X169215Y876085D03*
Y880885D03*
X154215D03*
Y876085D03*
X169215Y895685D03*
Y890885D03*
X154215Y895685D03*
Y890885D03*
X164200Y885700D03*
X158900D03*
X192963Y888625D03*
Y883625D03*
X188163Y888625D03*
X183363D03*
X178563D03*
Y883625D03*
X173763D03*
Y888625D03*
X183363Y883625D03*
X188163D03*
X113363Y884925D03*
X180000Y1424000D03*
Y1430000D03*
X186000Y1424000D03*
Y1430000D03*
X152000Y1377000D03*
Y1383000D03*
X158000Y1377000D03*
Y1383000D03*
X170000D03*
Y1377000D03*
X164000Y1383000D03*
Y1377000D03*
X102000Y1505500D03*
X177433Y1513685D03*
X182433D03*
X187433D03*
X192433D03*
X147433D03*
X152433D03*
X157433D03*
X162433D03*
X167433D03*
X172433D03*
X103000Y1511000D03*
X107433Y1513685D03*
X112433D03*
X117433D03*
X122433D03*
X127433D03*
X132433D03*
X137433D03*
X142433D03*
X290412Y6000D03*
X285412D03*
X280412D03*
X275412D03*
X270412D03*
X265412D03*
X260412D03*
X255412D03*
X250412D03*
X245412D03*
X240412D03*
X235412D03*
X230412D03*
X225412D03*
X220412D03*
X215412D03*
X210412D03*
X205412D03*
X200412D03*
X251200Y457900D03*
Y438300D03*
Y443100D03*
Y453100D03*
X291500Y451100D03*
Y446100D03*
X286700D03*
Y451100D03*
X281900D03*
Y446100D03*
X272300D03*
Y451100D03*
X277100Y446100D03*
Y451100D03*
X267752Y458160D03*
Y438560D03*
Y443360D03*
Y453360D03*
X257127Y448364D03*
X261927D03*
X211590Y427289D03*
X211190Y447189D03*
X197763Y888625D03*
Y883625D03*
X233074Y1429500D03*
X239274Y1429600D03*
X237235Y1419039D03*
X236974Y1425000D03*
X283000Y1492000D03*
X279000Y1498500D03*
X197433Y1513685D03*
X202433D03*
X207433D03*
X212433D03*
X217433D03*
X222433D03*
X227433D03*
X232433D03*
X237433D03*
X242433D03*
X247433D03*
X252433D03*
X257433D03*
X262433D03*
X267433D03*
X272433D03*
X277433D03*
X278646Y1509398D03*
Y1504398D03*
X288685Y1490063D03*
X385412Y6000D03*
X380412D03*
X375412D03*
X370412D03*
X365412D03*
X360412D03*
X355412D03*
X350412D03*
X345412D03*
X340412D03*
X335412D03*
X330412D03*
X325412D03*
X320412D03*
X315412D03*
X310412D03*
X305412D03*
X300412D03*
X295412D03*
X296300Y446100D03*
Y451100D03*
X380780Y1428599D03*
Y1422599D03*
Y1416599D03*
Y1410599D03*
X374780Y1428599D03*
Y1422599D03*
Y1416599D03*
Y1410599D03*
X293685Y1490063D03*
X298685D03*
X303685D03*
X308685D03*
X313685D03*
X318685D03*
X323685D03*
X328685D03*
X333685D03*
X338685D03*
X343685D03*
X348685D03*
X353685D03*
X358685D03*
X363685D03*
X368685D03*
X373685D03*
X378685D03*
X383685D03*
X380780Y1434599D03*
X374780D03*
X480412Y6000D03*
X475412D03*
X470412D03*
X465412D03*
X460412D03*
X455412D03*
X450412D03*
X445412D03*
X440412D03*
X435412D03*
X430412D03*
X425412D03*
X420412D03*
X415412D03*
X410412D03*
X405412D03*
X400412D03*
X395412D03*
X390412D03*
X388685Y1490063D03*
X393685D03*
X398685D03*
X403685D03*
X408685D03*
X413685D03*
X418685D03*
X423685D03*
X428685D03*
X433685D03*
X438685D03*
X443685D03*
X448685D03*
X453685D03*
X458685D03*
X463685D03*
X468685D03*
X473685D03*
X478685D03*
X575412Y6000D03*
X570412D03*
X565412D03*
X560412D03*
X555412D03*
X550412D03*
X545412D03*
X540412D03*
X535412D03*
X530412D03*
X525412D03*
X520412D03*
X515412D03*
X510412D03*
X505412D03*
X500412D03*
X495412D03*
X490412D03*
X485412D03*
X501000Y1494000D03*
X503000Y1499000D03*
X494500Y1490500D03*
X574937Y1513685D03*
X569937D03*
X564937D03*
X559937D03*
X554937D03*
X549937D03*
X544937D03*
X539937D03*
X534937D03*
X529937D03*
X524937D03*
X483685Y1490063D03*
X488685D03*
X503244Y1504378D03*
Y1509378D03*
X504937Y1513685D03*
X509937D03*
X514937D03*
X519937D03*
X513917Y1447297D03*
X507917D03*
X519717D03*
X670412Y6000D03*
X665412D03*
X660412D03*
X655412D03*
X650412D03*
X645412D03*
X640412D03*
X635412D03*
X630412D03*
X625412D03*
X620412D03*
X615412D03*
X610412D03*
X605412D03*
X600412D03*
X595412D03*
X590412D03*
X585412D03*
X580412D03*
X669937Y1513685D03*
X659937D03*
X654937D03*
X649937D03*
X644937D03*
X639937D03*
X634937D03*
X629937D03*
X624937D03*
X619937D03*
X614937D03*
X609937D03*
X604937D03*
X599937D03*
X594937D03*
X589937D03*
X584937D03*
X579937D03*
X664937D03*
X765412Y6000D03*
X760412D03*
X755412D03*
X750412D03*
X745412D03*
X740412D03*
X735412D03*
X730412D03*
X725412D03*
X720412D03*
X715412D03*
X710412D03*
X705412D03*
X700412D03*
X695412D03*
X690412D03*
X685412D03*
X680412D03*
X675412D03*
X722000Y1503500D03*
X718500Y1500000D03*
X680500Y1503500D03*
X674937Y1513685D03*
X688012Y1499118D03*
X693012D03*
X698012D03*
X703012D03*
X708012D03*
X713012D03*
X724000Y1509500D03*
X725551Y1513685D03*
X730551D03*
X735551D03*
X740551D03*
X745551D03*
X750551D03*
X755551D03*
X760551D03*
X765551D03*
X678500Y1510500D03*
X777465Y93947D03*
Y88947D03*
Y83947D03*
Y78947D03*
Y73947D03*
Y68947D03*
Y63947D03*
Y58947D03*
Y53947D03*
Y48947D03*
Y43947D03*
Y38947D03*
Y33947D03*
Y28947D03*
Y23947D03*
Y18947D03*
Y13947D03*
X778000Y9500D03*
X775412Y6000D03*
X770412D03*
X777465Y183947D03*
Y178947D03*
Y173947D03*
Y168947D03*
Y163947D03*
Y158947D03*
Y153947D03*
Y148947D03*
Y143947D03*
Y138947D03*
Y133947D03*
Y128947D03*
Y123947D03*
Y118947D03*
Y113947D03*
Y108947D03*
Y103947D03*
Y98947D03*
X809500Y197500D03*
X805522Y195764D03*
X808961Y201678D03*
Y206678D03*
Y211678D03*
Y216678D03*
Y236678D03*
Y231678D03*
Y226678D03*
Y221678D03*
Y241678D03*
X779022Y190764D03*
X784022Y194764D03*
X800522Y195764D03*
X795522D03*
X790522D03*
X826843Y409096D03*
Y404296D03*
Y399496D03*
X822043D03*
Y404296D03*
Y409096D03*
X807643Y408996D03*
Y404196D03*
Y399396D03*
X802843D03*
Y404196D03*
Y408996D03*
X826843Y419764D03*
Y424564D03*
Y429364D03*
X802843Y419664D03*
X807643D03*
X822043Y419764D03*
X802843Y429264D03*
Y424464D03*
X807643D03*
Y429264D03*
X822043Y429364D03*
Y424564D03*
X822400Y567100D03*
Y562300D03*
Y557500D03*
X817600D03*
Y562300D03*
Y567100D03*
X803200Y557400D03*
Y562200D03*
Y567000D03*
X798400Y557400D03*
Y562200D03*
Y567000D03*
X822400Y587368D03*
Y582568D03*
X817600D03*
Y587368D03*
X803200Y587268D03*
Y582468D03*
X798400D03*
Y587268D03*
X822400Y577768D03*
X817600D03*
X803200Y577668D03*
X798400D03*
X808300Y1197300D03*
X813100D03*
Y1206900D03*
Y1202100D03*
X808300D03*
Y1206900D03*
X794100Y1197300D03*
X789300D03*
X794100Y1202100D03*
Y1206900D03*
X789300Y1202100D03*
Y1206900D03*
X808300Y1227168D03*
Y1222368D03*
X813100D03*
Y1227168D03*
X794100D03*
Y1222368D03*
X789300D03*
Y1227168D03*
X813100Y1217568D03*
X808300D03*
X789300D03*
X794100D03*
X779500Y1491000D03*
X775000Y1495500D03*
X770551Y1513685D03*
X773528Y1510662D03*
Y1505662D03*
Y1500662D03*
X786803Y1490063D03*
X791803D03*
X796803D03*
X801803D03*
X806803D03*
X811803D03*
X816803D03*
X821803D03*
X826803D03*
X831803D03*
X836803D03*
X841803D03*
X846803D03*
X851803D03*
X856803D03*
X861803D03*
X887127Y254031D03*
X944200Y1083100D03*
X938900Y1103700D03*
X938800Y1109300D03*
X945200Y1398300D03*
Y1393500D03*
X950200Y1394500D03*
X866803Y1490063D03*
X871803D03*
X876803D03*
X881803D03*
X886803D03*
X891803D03*
X896803D03*
X901803D03*
X906803D03*
X911803D03*
X916803D03*
X921803D03*
X926803D03*
X931803D03*
X936803D03*
X941803D03*
X946803D03*
X951803D03*
X956803D03*
X1012000Y371369D03*
X1015537Y365911D03*
X1038200Y762300D03*
X1021194Y766883D03*
X1035594Y766983D03*
X1040394D03*
X1021194Y771683D03*
Y776483D03*
X1035594Y776583D03*
Y771783D03*
X1040394D03*
Y776583D03*
X1016394Y766883D03*
Y776483D03*
Y771683D03*
X997000Y1496000D03*
X993000Y1491500D03*
X961803Y1490063D03*
X966803D03*
X971803D03*
X976803D03*
X981803D03*
X986803D03*
X998126Y1503614D03*
Y1508614D03*
Y1513614D03*
X1003126D03*
X1008126D03*
X1013126D03*
X1018126D03*
X1023126D03*
X1028126D03*
X1033126D03*
X1038126D03*
X1043126D03*
X1048126D03*
X1053126D03*
X1068734Y195764D03*
X1064500Y197500D03*
X1065055Y201895D03*
Y206895D03*
Y211895D03*
Y216895D03*
Y226895D03*
Y231895D03*
Y236895D03*
Y241895D03*
Y221895D03*
X1148734Y195764D03*
X1143734D03*
X1138734D03*
X1133734D03*
X1128734D03*
X1123734D03*
X1118734D03*
X1113734D03*
X1103734D03*
X1098734D03*
X1093734D03*
X1088734D03*
X1083734D03*
X1078734D03*
X1073734D03*
X1075627Y374973D03*
X1075829Y380885D03*
X1119877Y408072D03*
Y403272D03*
Y398472D03*
X1124677D03*
Y403272D03*
Y408072D03*
X1100677Y407972D03*
Y403172D03*
Y398372D03*
X1105477D03*
Y403172D03*
Y407972D03*
X1119877Y423540D03*
Y428340D03*
Y418740D03*
X1124677Y428340D03*
Y423540D03*
Y418740D03*
X1105477Y428240D03*
Y423440D03*
X1100677D03*
Y428240D03*
X1105477Y418640D03*
X1100677D03*
X1076142Y386839D03*
X1057400Y771600D03*
X1057600Y776500D03*
X1067200Y786500D03*
X1062400D03*
Y781500D03*
X1057600Y786500D03*
Y781500D03*
X1067200Y791500D03*
X1062400D03*
X1067200Y796500D03*
X1062400D03*
X1057600D03*
Y791500D03*
X1128700Y1206500D03*
X1133500D03*
Y1201700D03*
X1128700D03*
X1133500Y1196900D03*
X1128700D03*
X1109600Y1197100D03*
X1114400D03*
X1109600Y1201900D03*
X1114400D03*
Y1206700D03*
X1109600D03*
X1128500Y1225700D03*
X1133300D03*
X1109400Y1221100D03*
X1114200D03*
Y1225900D03*
X1109400D03*
X1133300Y1220900D03*
X1128500D03*
X1133300Y1216100D03*
X1128500D03*
X1109400Y1216300D03*
X1114200D03*
X1087933Y1411323D03*
X1082933D03*
X1077933D03*
X1095567Y1426057D03*
X1117200Y1346700D03*
X1058126Y1513614D03*
X1061675Y1510352D03*
X1065210Y1506817D03*
X1066638Y1472408D03*
Y1467408D03*
Y1462408D03*
Y1457408D03*
Y1452408D03*
Y1447408D03*
Y1442408D03*
X1095567Y1431057D03*
Y1436057D03*
Y1441057D03*
Y1446057D03*
Y1451057D03*
Y1456057D03*
Y1461057D03*
Y1466057D03*
X1096039Y1505861D03*
X1099575Y1509397D03*
X1103110Y1512932D03*
X1107798Y1513685D03*
X1112798D03*
X1117798D03*
X1122798D03*
X1127798D03*
X1132798D03*
X1137798D03*
X1142798D03*
X1147798D03*
X1095567Y1471057D03*
X1066638Y1502408D03*
X1115000Y1485000D03*
X1118000Y1480500D03*
X1112000D03*
X1234500Y6000D03*
X1243844D03*
X1238844D03*
X1230409Y7565D03*
Y12565D03*
Y17565D03*
Y22565D03*
Y27565D03*
Y32565D03*
Y37565D03*
Y42565D03*
Y47565D03*
Y52565D03*
Y57565D03*
Y62565D03*
Y67565D03*
Y72565D03*
Y77565D03*
Y82565D03*
Y87565D03*
Y92565D03*
X1229000Y189500D03*
X1230409Y97565D03*
Y102565D03*
Y107565D03*
Y112565D03*
Y117565D03*
Y122565D03*
Y127565D03*
Y132565D03*
Y137565D03*
Y142565D03*
Y147565D03*
Y152565D03*
Y157565D03*
Y162565D03*
Y167565D03*
Y172565D03*
Y177565D03*
Y182565D03*
X1225000Y194000D03*
X1218734Y195764D03*
X1213734D03*
X1208734D03*
X1203734D03*
X1198734D03*
X1193734D03*
X1188734D03*
X1183734D03*
X1178734D03*
X1173734D03*
X1168734D03*
X1163734D03*
X1158734D03*
X1153734D03*
X1151100Y1179300D03*
X1155900D03*
X1151100Y1184100D03*
X1155900D03*
Y1188900D03*
X1151100D03*
X1245500Y1500500D03*
X1208000Y1502500D03*
X1234783Y1499118D03*
X1229783D03*
X1224783D03*
X1219783D03*
X1214783D03*
X1239783D03*
X1152798Y1513685D03*
X1157798D03*
X1162798D03*
X1167798D03*
X1172798D03*
X1177798D03*
X1182798D03*
X1187798D03*
X1192798D03*
X1197798D03*
X1202798D03*
X1205500Y1509000D03*
X1338844Y6000D03*
X1333844D03*
X1328844D03*
X1323844D03*
X1318844D03*
X1313844D03*
X1308844D03*
X1303844D03*
X1298844D03*
X1293844D03*
X1288844D03*
X1283844D03*
X1278844D03*
X1273844D03*
X1268844D03*
X1263844D03*
X1258844D03*
X1253844D03*
X1248844D03*
X1249000Y1504500D03*
X1328464Y1513685D03*
X1333464D03*
X1338464D03*
X1293464D03*
X1298464D03*
X1303464D03*
X1308464D03*
X1313464D03*
X1318464D03*
X1323464D03*
X1250500Y1510500D03*
X1253464Y1513685D03*
X1258464D03*
X1263464D03*
X1268464D03*
X1273464D03*
X1278464D03*
X1283464D03*
X1288464D03*
X1433844Y6000D03*
X1428844D03*
X1423844D03*
X1418844D03*
X1413844D03*
X1408844D03*
X1403844D03*
X1398844D03*
X1393844D03*
X1388844D03*
X1383844D03*
X1378844D03*
X1373844D03*
X1368844D03*
X1363844D03*
X1358844D03*
X1353844D03*
X1348844D03*
X1343844D03*
X1385474Y1429500D03*
X1380074D03*
X1383374Y1425000D03*
X1383674Y1419000D03*
X1433500Y1490500D03*
X1428500Y1494000D03*
X1403500Y1513500D03*
X1398500D03*
X1363464Y1513685D03*
X1368464D03*
X1373464D03*
X1378464D03*
X1383464D03*
X1388464D03*
X1393464D03*
X1353464D03*
X1358464D03*
X1343464D03*
X1348464D03*
X1408464D03*
X1413464D03*
X1418464D03*
X1423464D03*
X1425890Y1510111D03*
Y1505111D03*
Y1500111D03*
X1528844Y6000D03*
X1523844D03*
X1518844D03*
X1513844D03*
X1508844D03*
X1503844D03*
X1498844D03*
X1493844D03*
X1488844D03*
X1483844D03*
X1478844D03*
X1473844D03*
X1468844D03*
X1463844D03*
X1458844D03*
X1453844D03*
X1448844D03*
X1443844D03*
X1438844D03*
X1439716Y1490063D03*
X1444716D03*
X1449716D03*
X1454716D03*
X1459716D03*
X1464716D03*
X1469716D03*
X1474716D03*
X1479716D03*
X1484716D03*
X1489716D03*
X1494716D03*
X1499716D03*
X1504716D03*
X1509716D03*
X1514716D03*
X1519716D03*
X1524716D03*
X1529716D03*
X1623844Y6000D03*
X1618844D03*
X1613844D03*
X1608844D03*
X1603844D03*
X1598844D03*
X1593844D03*
X1588844D03*
X1583844D03*
X1578844D03*
X1573844D03*
X1568844D03*
X1563844D03*
X1558844D03*
X1553844D03*
X1548844D03*
X1543844D03*
X1538844D03*
X1533844D03*
X1534716Y1490063D03*
X1539716D03*
X1544716D03*
X1549716D03*
X1554716D03*
X1559716D03*
X1564716D03*
X1569716D03*
X1574716D03*
X1579716D03*
X1584716D03*
X1589716D03*
X1594716D03*
X1599716D03*
X1604716D03*
X1609716D03*
X1614716D03*
X1619716D03*
X1624716D03*
X1718844Y6000D03*
X1713844D03*
X1708844D03*
X1703844D03*
X1698844D03*
X1693844D03*
X1688844D03*
X1683844D03*
X1678844D03*
X1673844D03*
X1668844D03*
X1663844D03*
X1658844D03*
X1653844D03*
X1648844D03*
X1643844D03*
X1638844D03*
X1633844D03*
X1628844D03*
X1667359Y434407D03*
Y439207D03*
Y429607D03*
X1662559D03*
Y434407D03*
Y439207D03*
X1649500Y1497500D03*
X1646000Y1492000D03*
X1720968Y1513685D03*
X1715968D03*
X1710968D03*
X1705968D03*
X1700968D03*
X1695968D03*
X1690968D03*
X1685968D03*
X1680968D03*
X1670968D03*
X1675968D03*
X1629716Y1490063D03*
X1634716D03*
X1639716D03*
X1650488Y1504165D03*
Y1509165D03*
X1650968Y1513685D03*
X1655968D03*
X1660968D03*
X1665968D03*
X1813844Y6000D03*
X1808844D03*
X1803844D03*
X1798844D03*
X1793844D03*
X1788844D03*
X1783844D03*
X1778844D03*
X1773844D03*
X1768844D03*
X1763844D03*
X1758844D03*
X1753844D03*
X1748844D03*
X1743844D03*
X1738844D03*
X1733844D03*
X1728844D03*
X1723844D03*
X1814463Y449725D03*
Y454725D03*
X1804900Y451800D03*
X1809915Y461785D03*
Y446985D03*
Y456985D03*
Y442185D03*
X1799600Y451800D03*
X1794915Y461785D03*
Y446985D03*
Y456985D03*
Y442185D03*
X1751774Y430510D03*
X1753959Y450607D03*
X1741159Y873707D03*
X1736359D03*
X1741159Y864107D03*
X1736359D03*
X1741159Y868907D03*
X1736359D03*
X1766526Y1429400D03*
X1760326Y1429500D03*
X1763926Y1419000D03*
X1763626Y1425000D03*
X1786004Y1513500D03*
X1780968Y1513685D03*
X1775968D03*
X1770968D03*
X1765968D03*
X1760968D03*
X1755968D03*
X1750968D03*
X1745968D03*
X1740968D03*
X1796004Y1513500D03*
X1801004D03*
X1806004D03*
X1811004D03*
X1816004D03*
X1730968Y1513685D03*
X1725968D03*
X1791004Y1513500D03*
X1735968Y1513685D03*
X1913844Y6000D03*
X1908844D03*
X1903844D03*
X1898844D03*
X1893844D03*
X1888844D03*
X1883844D03*
X1878844D03*
X1873844D03*
X1868844D03*
X1863844D03*
X1858844D03*
X1853844D03*
X1848844D03*
X1843844D03*
X1838844D03*
X1833844D03*
X1828844D03*
X1823844D03*
X1818844D03*
X1838463Y454725D03*
Y449725D03*
X1819263D03*
Y454725D03*
X1833663D03*
Y449725D03*
X1828863D03*
Y454725D03*
X1824063D03*
Y449725D03*
X1912663Y888925D03*
Y883925D03*
X1869115Y876385D03*
Y891185D03*
Y881185D03*
Y895985D03*
X1873800Y886300D03*
X1884115Y876385D03*
X1898263Y883925D03*
Y888925D03*
X1903063D03*
Y883925D03*
X1907863D03*
Y888925D03*
X1884115Y891185D03*
Y881185D03*
Y895985D03*
X1893463Y888925D03*
Y883925D03*
X1879100Y886300D03*
X1888663Y888925D03*
Y883925D03*
X1828363Y884925D03*
X1869500Y1503500D03*
X1865500Y1500000D03*
X1829500Y1501500D03*
X1826500Y1506500D03*
X1855256Y1499118D03*
X1850256D03*
X1845256D03*
X1840256D03*
X1826040Y1513315D03*
X1821040D03*
X1835256Y1499118D03*
X1860256D03*
X1871157Y1509110D03*
X1871582Y1513685D03*
X1876582D03*
X1881582D03*
X1886582D03*
X1891582D03*
X1896582D03*
X1901582D03*
X1906582D03*
X1911582D03*
X1928843Y8985D03*
Y93985D03*
Y88985D03*
Y83985D03*
Y78985D03*
Y73985D03*
Y68985D03*
Y63985D03*
Y58985D03*
Y53985D03*
Y48985D03*
Y43985D03*
Y38985D03*
Y28985D03*
Y23985D03*
Y18985D03*
Y13985D03*
Y33985D03*
X1923844Y6000D03*
X1918844D03*
X1928843Y98985D03*
Y188985D03*
Y183985D03*
Y178985D03*
Y173985D03*
Y168985D03*
Y163985D03*
Y158985D03*
Y153985D03*
Y148985D03*
Y143985D03*
Y138985D03*
Y133985D03*
Y128985D03*
Y123985D03*
Y118985D03*
Y113985D03*
Y108985D03*
Y103985D03*
Y283985D03*
Y278985D03*
Y273985D03*
Y268985D03*
Y263985D03*
Y258985D03*
Y253985D03*
Y248985D03*
Y243985D03*
Y238985D03*
Y233985D03*
Y228985D03*
Y223985D03*
Y218985D03*
Y213985D03*
Y208985D03*
Y203985D03*
Y198985D03*
Y193985D03*
Y378985D03*
Y373985D03*
Y368985D03*
Y363985D03*
Y358985D03*
Y353985D03*
Y348985D03*
Y343985D03*
Y338985D03*
Y333985D03*
Y328985D03*
Y323985D03*
Y318985D03*
Y313985D03*
Y308985D03*
Y303985D03*
Y298985D03*
Y293985D03*
Y288985D03*
Y418985D03*
Y433985D03*
Y428985D03*
Y423985D03*
Y473985D03*
Y468985D03*
Y463985D03*
Y458985D03*
Y453985D03*
Y448985D03*
Y443985D03*
Y438985D03*
Y413985D03*
Y408985D03*
Y403985D03*
Y398985D03*
Y393985D03*
Y388985D03*
Y383985D03*
Y568985D03*
Y563985D03*
Y558985D03*
Y553985D03*
Y548985D03*
Y543985D03*
Y538985D03*
Y533985D03*
Y528985D03*
Y523985D03*
Y518985D03*
Y513985D03*
Y508985D03*
Y503985D03*
Y498985D03*
Y493985D03*
Y488985D03*
Y483985D03*
Y478985D03*
Y663985D03*
Y658985D03*
Y653985D03*
Y648985D03*
Y643985D03*
Y638985D03*
Y633985D03*
Y628985D03*
Y623985D03*
Y618985D03*
Y613985D03*
Y608985D03*
Y603985D03*
Y598985D03*
Y593985D03*
Y588985D03*
Y583985D03*
Y578985D03*
Y573985D03*
Y758985D03*
Y753985D03*
Y748985D03*
Y743985D03*
Y738985D03*
Y733985D03*
Y728985D03*
Y723985D03*
Y718985D03*
Y713985D03*
Y708985D03*
Y703985D03*
Y698985D03*
Y693985D03*
Y688985D03*
Y683985D03*
Y678985D03*
Y673985D03*
Y668985D03*
Y853985D03*
Y848985D03*
Y843985D03*
Y838985D03*
Y833985D03*
Y828985D03*
Y823985D03*
Y818985D03*
Y813985D03*
Y808985D03*
Y803985D03*
Y798985D03*
Y793985D03*
Y788985D03*
Y783985D03*
Y778985D03*
Y773985D03*
Y768985D03*
Y763985D03*
Y918985D03*
Y913985D03*
Y908985D03*
Y903985D03*
Y898985D03*
Y893985D03*
Y888985D03*
Y883985D03*
Y878985D03*
Y873985D03*
Y868985D03*
Y863985D03*
Y858985D03*
Y948985D03*
Y943985D03*
Y938985D03*
Y933985D03*
Y928985D03*
Y923985D03*
Y1043985D03*
Y1038985D03*
Y1033985D03*
Y1028985D03*
Y1023985D03*
Y1018985D03*
Y1013985D03*
Y1008985D03*
Y1003985D03*
Y998985D03*
Y993985D03*
Y988985D03*
Y983985D03*
Y978985D03*
Y973985D03*
Y968985D03*
Y963985D03*
Y958985D03*
Y953985D03*
Y1143985D03*
Y1138985D03*
Y1133985D03*
Y1128985D03*
Y1123985D03*
Y1118985D03*
Y1113985D03*
Y1108985D03*
Y1103985D03*
Y1098985D03*
Y1093985D03*
Y1088985D03*
Y1083985D03*
Y1078985D03*
Y1073985D03*
Y1068985D03*
Y1063985D03*
Y1058985D03*
Y1053985D03*
Y1048985D03*
Y1238985D03*
Y1233985D03*
Y1228985D03*
Y1223985D03*
Y1218985D03*
Y1213985D03*
Y1208985D03*
Y1203985D03*
Y1198985D03*
Y1193985D03*
Y1188985D03*
Y1183985D03*
Y1178985D03*
Y1173985D03*
Y1168985D03*
Y1163985D03*
Y1158985D03*
Y1153985D03*
Y1148985D03*
Y1288985D03*
Y1293985D03*
Y1298985D03*
Y1303985D03*
Y1308985D03*
Y1313985D03*
Y1318985D03*
Y1323985D03*
Y1328985D03*
Y1333985D03*
Y1283985D03*
Y1278985D03*
Y1273985D03*
Y1268985D03*
Y1263985D03*
Y1258985D03*
Y1253985D03*
Y1248985D03*
Y1243985D03*
Y1348985D03*
Y1353985D03*
Y1358985D03*
Y1363985D03*
Y1368985D03*
Y1373985D03*
Y1378985D03*
Y1383985D03*
Y1388985D03*
Y1393985D03*
Y1398985D03*
Y1403985D03*
Y1408985D03*
Y1413985D03*
Y1418985D03*
Y1423985D03*
Y1428985D03*
Y1338985D03*
Y1343985D03*
Y1448985D03*
Y1443985D03*
Y1433985D03*
Y1438985D03*
X1920000Y1458000D03*
X1917500Y1463500D03*
X1916582Y1513685D03*
X1917031Y1509134D03*
Y1504134D03*
Y1499134D03*
Y1494134D03*
Y1489134D03*
Y1484134D03*
Y1479134D03*
Y1474134D03*
Y1469134D03*
X1926500Y1455000D03*
G54D14*
X62263Y877225D03*
X160090Y439489D03*
X1702859Y442907D03*
X1777263Y877225D03*
G54D23*
X59963Y887525D03*
X157790Y449789D03*
X1021763Y1114199D03*
X996700Y1099000D03*
X978700Y1126800D03*
X1700559Y453207D03*
X1774963Y887525D03*
G54D32*
X47329Y895302D03*
X48763Y900772D03*
X140716Y453101D03*
X146590Y463036D03*
X192425Y869073D03*
X126263Y914025D03*
X103263Y909525D03*
X112763Y912025D03*
X120496Y1405549D03*
X125469Y1373872D03*
X200879Y470744D03*
X213590Y474289D03*
X224090Y476289D03*
X201778Y878425D03*
X279700Y1428000D03*
X291450Y439719D03*
X298690Y441316D03*
X296183Y433389D03*
X298486Y454996D03*
X508196Y1434276D03*
X508099Y1439755D03*
X646102Y1321750D03*
X641102D03*
X646200Y1420576D03*
X641200D03*
X665700Y1463500D03*
Y1468500D03*
Y1458000D03*
Y1453000D03*
X858500Y845700D03*
X858100Y850000D03*
X848300Y847700D03*
X844800Y895902D03*
X845732Y891713D03*
X847881Y1198981D03*
X810000Y1290500D03*
X810221Y1339832D03*
X810000Y1377500D03*
X943904Y372485D03*
X896476Y502611D03*
X913276Y501747D03*
X950000Y1081000D03*
X941456Y1182512D03*
X951723Y1177569D03*
X873200Y1208700D03*
X942100Y1193300D03*
X914031Y1243291D03*
X941559Y1408198D03*
Y1403198D03*
X1038179Y413863D03*
X1022646Y401202D03*
X1021469Y390508D03*
X1047434Y429008D03*
X977047Y393217D03*
X996452Y404314D03*
X1027862Y414122D03*
X1004412Y559568D03*
X995316Y554256D03*
X978415Y547627D03*
X968979Y542300D03*
X970000Y1121500D03*
X1000000Y1094500D03*
X973500Y1080500D03*
X1013000Y1108500D03*
X978500Y1122000D03*
X990200Y1118300D03*
X988800Y1126800D03*
X1017700Y1118304D03*
X996900Y1124500D03*
X1016300Y1113500D03*
X982227Y1150350D03*
X966985Y1393900D03*
X961857D03*
X1071421Y443932D03*
X1074279Y407249D03*
X1059563Y425123D03*
X1130800Y472900D03*
X1110767Y1309112D03*
X1156110Y473330D03*
X1152600Y468470D03*
X1184500Y570000D03*
X1177350Y597792D03*
X1198184Y740895D03*
X1192158Y736695D03*
X1197842Y732495D03*
X1192853Y728295D03*
X1198213Y724095D03*
X1192568Y719895D03*
X1185718Y1333821D03*
X1160612Y1401773D03*
X1247682Y1421608D03*
X1688216Y461478D03*
X1689359Y466454D03*
X1817496Y437282D03*
X1743859Y475207D03*
X1766859Y479707D03*
X1754525Y478316D03*
X1762442Y895401D03*
X1763763Y900772D03*
X1825896Y440582D03*
X1835508Y444107D03*
X1835092Y435418D03*
X1907800Y871200D03*
X1841263Y914025D03*
X1827863Y912525D03*
X1818263Y909525D03*
G54D41*
X109826Y904041D03*
X207653Y466305D03*
X1750422Y469723D03*
X1824826Y904041D03*
G54D50*
X516898Y1438421D03*
X1026700Y1133600D03*
X1013231Y1098071D03*
X986500Y1122200D03*
G54D24*
X32263Y878825D03*
X132190Y444689D03*
X127141Y904744D03*
X224968Y467008D03*
X969900Y1132600D03*
X1672859Y444507D03*
X1767737Y470426D03*
X1747263Y878825D03*
X1842141Y904744D03*
G54D15*
X62263Y880825D03*
X160090Y443089D03*
X1702859Y446507D03*
X1777263Y880825D03*
G54D42*
X143111Y874400D03*
X108489D03*
X240938Y436664D03*
X206316D03*
X1783707Y440082D03*
X1749085D03*
X1823489Y874400D03*
X1858111D03*
G54D51*
X669470Y1467800D03*
X1022935Y1130078D03*
X1016645Y1106842D03*
G54D60*
X974015Y284449D03*
X986614D03*
X1002362D03*
X1014960D03*
X1030709D03*
X1043307D03*
X974015Y261812D03*
X986614D03*
X1002362D03*
X1014960D03*
X1030709D03*
X1043307D03*
X974015Y278544D03*
X1002362D03*
X1030709D03*
X974015Y267717D03*
X1002362D03*
X1030709D03*
X974015Y255906D03*
X1002362D03*
X1030709D03*
X986614Y278544D03*
X1014960D03*
X1043307D03*
X986614Y267717D03*
X1014960D03*
X1043307D03*
X986614Y255906D03*
X1014960D03*
X1043307D03*
X974015Y307087D03*
X986614D03*
X1002362D03*
X1014960D03*
X1030709D03*
X1043307D03*
X974015Y312993D03*
X1002362D03*
X1030709D03*
X974015Y301182D03*
X1002362D03*
X1030709D03*
X974015Y290355D03*
X1002362D03*
X1030709D03*
X986614Y312993D03*
X1014960D03*
X1043307D03*
X986614Y301182D03*
X1014960D03*
X1043307D03*
X986614Y290355D03*
X1014960D03*
X1043307D03*
X1101405Y1120040D03*
X1119633D03*
X1101405Y1132638D03*
X1119633D03*
X1108098Y1120040D03*
X1126326D03*
X1108098Y1132638D03*
X1126326D03*
G54D33*
X90709Y1485118D03*
X80709D03*
X70709D03*
X711181D03*
X701181D03*
X691181D03*
X1237953D03*
X1227953D03*
X1217953D03*
X1858425D03*
X1848425D03*
X1838425D03*
G54D70*
X995581Y1114452D03*
Y1108546D03*
X1007793D03*
Y1114452D03*
G54D43*
X184252Y1445275D03*
Y1466929D03*
X167716Y1445275D03*
Y1466929D03*
X233858Y1445275D03*
Y1466929D03*
X217322Y1445275D03*
Y1466929D03*
X200787Y1445275D03*
Y1466929D03*
X581102Y1445275D03*
Y1466929D03*
X564567Y1445275D03*
Y1466929D03*
X548031Y1445275D03*
Y1466929D03*
X614173Y1445275D03*
Y1466929D03*
X597637Y1445275D03*
Y1466929D03*
X1331496Y1445275D03*
Y1466929D03*
X1314960Y1445275D03*
Y1466929D03*
X1381102Y1445275D03*
Y1466929D03*
X1364566Y1445275D03*
Y1466929D03*
X1348031Y1445275D03*
Y1466929D03*
X1711811Y1445275D03*
Y1466929D03*
X1695275Y1445275D03*
Y1466929D03*
X1761417Y1445275D03*
Y1466929D03*
X1744881Y1445275D03*
Y1466929D03*
X1728346Y1445275D03*
Y1466929D03*
G54D16*
X94463Y908025D03*
X192290Y470289D03*
X512746Y1442322D03*
X1735059Y473707D03*
X1809463Y908025D03*
G54D52*
X669470Y1464200D03*
X1022935Y1126478D03*
X1016645Y1103242D03*
G54D61*
X1021393Y1118601D03*
G54D34*
G01X32263Y879025D02*
Y888025D01*
X45010Y900772D01*
X48763D01*
G01D02*
X59516D01*
X64563Y895725D01*
Y894025D01*
G01X146590Y463036D02*
X157343D01*
X162390Y457989D01*
Y456289D01*
G01X132190Y444889D02*
Y452389D01*
X142837Y463036D01*
X146590D01*
G01X143111Y874400D02*
X129700D01*
X127141Y876959D01*
Y898944D01*
G01X108489Y874400D02*
X118638D01*
X121736Y877498D01*
Y900224D01*
G01X209374Y1416300D02*
X209274Y1416200D01*
X188674D01*
X188274Y1416600D01*
G01X240938Y436664D02*
X227527D01*
X224968Y439223D01*
Y461208D01*
G01X206316Y436664D02*
X218409D01*
X220968Y439223D01*
Y457539D01*
X219563Y458944D01*
Y462488D01*
G01X466941Y-145664D02*
Y-225664D01*
G01D02*
X1593241D01*
G01X462941Y-129664D02*
G02I-12000J0D01*
G01X457791D02*
G02I-6850J0D01*
G01X450941Y-145664D02*
Y-113664D01*
G01X466941Y-129664D02*
X434941D01*
G01X466941Y-145664D02*
X1593241D01*
G01X466941Y-181164D02*
X1593241D01*
G01X508924Y1421605D02*
X506373Y1424156D01*
X505224D01*
G01X508099Y1439755D02*
X506135D01*
X504435Y1438055D01*
X501699D01*
G01X512796Y1442322D02*
Y1438558D01*
X512849Y1438505D01*
G01D02*
X509349D01*
X508099Y1439755D01*
G01X501699Y1438055D02*
Y1442995D01*
X503035Y1444331D01*
G01X730341Y1446725D02*
X720225D01*
X717500Y1444000D01*
X658000D01*
G01D02*
X640553D01*
X637972Y1441419D01*
G01X624750Y1461250D02*
Y1472113D01*
X646837Y1494200D01*
G01X815148Y654937D02*
X805657D01*
X752200Y601480D01*
Y572300D01*
G01X719100Y1463600D02*
X722288D01*
X724248Y1465560D01*
G01X805741Y-145664D02*
Y-225664D01*
G01X859086Y1290016D02*
Y1284010D01*
X859113Y1283983D01*
G01X860000Y1404984D02*
Y1410843D01*
G01X842500Y1404984D02*
Y1411343D01*
G01X943241Y-145664D02*
Y-225664D01*
G01X1262400Y1024700D02*
X1247898Y1039202D01*
X896702D01*
X895500Y1038000D01*
G01X871589Y1290016D02*
Y1284014D01*
X871556Y1283981D01*
G01X884060Y1290048D02*
Y1283985D01*
X884056Y1283981D01*
G01X876500Y1404984D02*
Y1410843D01*
G01X1027563Y1114199D02*
X1032201D01*
X1032361Y1114039D01*
G01X1013231Y1094621D02*
Y1089300D01*
G01X980000Y1112000D02*
X978500Y1113500D01*
Y1122000D01*
G01D02*
Y1126800D01*
G01D02*
X976706D01*
X976456Y1126550D01*
X974200D01*
G01X980500Y1092000D02*
X978250Y1089750D01*
Y1084500D01*
G01X1058241Y-145664D02*
Y-225664D01*
G01X1225741Y-145664D02*
Y-225664D01*
G01X1243500Y393600D02*
X1248500D01*
G01X1294624Y358802D02*
X1281346D01*
X1269568Y370580D01*
Y386062D01*
X1262030Y393600D01*
X1248500D01*
G01X1327900Y1416500D02*
X1347100D01*
X1347400Y1416200D01*
G01X1395741Y-145664D02*
Y-225664D01*
G01X1367514Y397100D02*
X1475445D01*
X1475650Y396895D01*
X1477888D01*
X1478093Y397100D01*
X1487014D01*
G01X1362514D02*
X1367514D01*
G01X1345215Y533601D02*
Y430485D01*
X1367514Y408186D01*
Y397100D01*
G01X1487014D02*
X1492014D01*
G01X1593241Y-145664D02*
Y-225664D01*
G01X1621241Y-129664D02*
G02I-12000J0D01*
G01X1616091D02*
G02I-6850J0D01*
G01X1609241Y-145664D02*
Y-113664D01*
G01X1625241Y-129664D02*
X1593241D01*
G01X1672859Y444707D02*
Y453707D01*
X1685606Y466454D01*
X1689359D01*
G01X1705159Y459707D02*
Y461407D01*
X1700112Y466454D01*
X1689359D01*
G01X1735126Y1416300D02*
X1716226D01*
X1716026Y1416500D01*
G01X1783707Y440082D02*
X1770296D01*
X1767737Y442641D01*
Y464626D01*
G01X1749085Y440082D02*
X1759234D01*
X1762332Y443180D01*
Y465906D01*
G01X1747263Y879025D02*
Y888025D01*
X1760010Y900772D01*
X1763763D01*
G01D02*
X1774516D01*
X1779563Y895725D01*
Y894025D01*
G01X1858111Y874400D02*
X1844700D01*
X1842141Y876959D01*
Y898944D01*
G01X1823489Y874400D02*
X1833638D01*
X1836763Y877525D01*
Y880501D01*
X1836736Y880528D01*
Y900224D01*
X127988Y67319D03*
Y71319D03*
Y76319D03*
Y80319D03*
X134983Y65269D03*
Y61269D03*
Y56769D03*
Y52769D03*
X127988Y520075D03*
Y524075D03*
Y529075D03*
Y533075D03*
X134983Y518025D03*
Y514025D03*
Y509525D03*
Y505525D03*
X127988Y972831D03*
Y976831D03*
Y981831D03*
Y985831D03*
X134983Y970781D03*
Y966781D03*
Y962281D03*
Y958281D03*
X252200Y67319D03*
Y71319D03*
Y76319D03*
Y80319D03*
X259195Y65269D03*
Y61269D03*
Y56769D03*
Y52769D03*
X252200Y520075D03*
Y524075D03*
Y529075D03*
Y533075D03*
X259195Y518025D03*
Y514025D03*
Y509525D03*
Y505525D03*
X252200Y972831D03*
Y976831D03*
Y981831D03*
Y985831D03*
X259195Y970781D03*
Y966781D03*
Y962281D03*
Y958281D03*
X376413Y67319D03*
Y71319D03*
Y76319D03*
Y80319D03*
X383408Y65269D03*
Y61269D03*
Y56769D03*
Y52769D03*
X376413Y520075D03*
Y524075D03*
Y529075D03*
Y533075D03*
X383408Y518025D03*
Y514025D03*
Y509525D03*
Y505525D03*
X376413Y972831D03*
Y976831D03*
Y981831D03*
Y985831D03*
X383408Y970781D03*
Y966781D03*
Y962281D03*
Y958281D03*
X500625Y67319D03*
Y71319D03*
Y76319D03*
Y80319D03*
X507620Y65269D03*
Y61269D03*
Y56769D03*
Y52769D03*
X500625Y520075D03*
Y524075D03*
Y529075D03*
Y533075D03*
X507620Y518025D03*
Y514025D03*
Y509525D03*
Y505525D03*
X500625Y972831D03*
Y976831D03*
Y981831D03*
Y985831D03*
X507620Y970781D03*
Y966781D03*
Y962281D03*
Y958281D03*
X500000Y1472000D03*
X624838Y67319D03*
Y71319D03*
Y76319D03*
Y80319D03*
X631833Y65269D03*
Y61269D03*
Y56769D03*
Y52769D03*
X624838Y520075D03*
Y524075D03*
Y529075D03*
Y533075D03*
X631833Y518025D03*
Y514025D03*
Y509525D03*
Y505525D03*
X624838Y972831D03*
Y976831D03*
Y981831D03*
Y985831D03*
X631833Y970781D03*
Y966781D03*
Y962281D03*
Y958281D03*
X749051Y67319D03*
Y71319D03*
Y76319D03*
Y80319D03*
X756046Y65269D03*
Y61269D03*
Y56769D03*
Y52769D03*
X749051Y520075D03*
Y524075D03*
Y529075D03*
Y533075D03*
X756046Y518025D03*
Y514025D03*
Y509525D03*
Y505525D03*
X749051Y972831D03*
Y976831D03*
Y981831D03*
Y985831D03*
X756046Y970781D03*
Y966781D03*
Y962281D03*
Y958281D03*
X918400Y760750D03*
X1279400Y68650D03*
X1275400D03*
X1270400D03*
X1266400D03*
X1252750Y53650D03*
X1256750D03*
X1261250D03*
X1265250D03*
X1279400Y521406D03*
X1275400D03*
X1270400D03*
X1266400D03*
X1252750Y506406D03*
X1256750D03*
X1261250D03*
X1265250D03*
X1273975Y972831D03*
Y976831D03*
Y981831D03*
Y985831D03*
X1257490Y970361D03*
Y966361D03*
Y961861D03*
Y957861D03*
X1403613Y68650D03*
X1399613D03*
X1394613D03*
X1390613D03*
X1376963Y53650D03*
X1380963D03*
X1385463D03*
X1389463D03*
X1403613Y521406D03*
X1399613D03*
X1394613D03*
X1390613D03*
X1376963Y506406D03*
X1380963D03*
X1385463D03*
X1389463D03*
X1398188Y972831D03*
Y976831D03*
Y981831D03*
Y985831D03*
X1381663Y970381D03*
Y966381D03*
Y961881D03*
Y957881D03*
X1527825Y68650D03*
X1523825D03*
X1518825D03*
X1514825D03*
X1501175Y53650D03*
X1505175D03*
X1509675D03*
X1513675D03*
X1527825Y521406D03*
X1523825D03*
X1518825D03*
X1514825D03*
X1501175Y506406D03*
X1505175D03*
X1509675D03*
X1513675D03*
X1522400Y972831D03*
Y976831D03*
Y981831D03*
Y985831D03*
X1505875Y970321D03*
Y966321D03*
Y961821D03*
Y957821D03*
X1625388Y53650D03*
Y506406D03*
X1652038Y68650D03*
X1648038D03*
X1643038D03*
X1639038D03*
X1629388Y53650D03*
X1633888D03*
X1637888D03*
X1652038Y521406D03*
X1648038D03*
X1643038D03*
X1639038D03*
X1629388Y506406D03*
X1633888D03*
X1637888D03*
X1646613Y972831D03*
Y976831D03*
Y981831D03*
Y985831D03*
X1630088Y970881D03*
Y966881D03*
Y962381D03*
Y958381D03*
X1776250Y68650D03*
X1772250D03*
X1767250D03*
X1763250D03*
X1749600Y53650D03*
X1753600D03*
X1758100D03*
X1762100D03*
X1776250Y521406D03*
X1772250D03*
X1767250D03*
X1763250D03*
X1749600Y506406D03*
X1753600D03*
X1758100D03*
X1762100D03*
X1770825Y972831D03*
Y976831D03*
Y981831D03*
Y985831D03*
X1754340Y970361D03*
Y966361D03*
Y961861D03*
Y957861D03*
X1900463Y68650D03*
X1896463D03*
X1891463D03*
X1887463D03*
X1873813Y53650D03*
X1877813D03*
X1882313D03*
X1886313D03*
X1900463Y521406D03*
X1896463D03*
X1891463D03*
X1887463D03*
X1873813Y506406D03*
X1877813D03*
X1882313D03*
X1886313D03*
X1895038Y972831D03*
Y976831D03*
Y981831D03*
Y985831D03*
X1878553Y970361D03*
Y966361D03*
Y961861D03*
Y957861D03*
G54D25*
X32263Y873225D03*
X132190Y439089D03*
X127141Y899144D03*
X224968Y461408D03*
X969900Y1127000D03*
X1672859Y438907D03*
X1767737Y464826D03*
X1747263Y873225D03*
X1842141Y899144D03*
G54D35*
X173228Y55118D03*
X421653Y94488D03*
X670078Y55118D03*
X1343701D03*
X1592126Y94488D03*
X1840551Y55118D03*
G54D26*
X56763Y874225D03*
Y881825D03*
X48763Y874225D03*
Y881825D03*
X40763Y874225D03*
Y881825D03*
X154590Y436489D03*
Y444089D03*
X146590Y436489D03*
Y444089D03*
X138590Y436489D03*
Y444089D03*
X175763Y895225D03*
Y902825D03*
X191763Y895225D03*
Y902825D03*
X183763Y895225D03*
Y902825D03*
X273590Y457489D03*
Y465089D03*
X289590Y457489D03*
Y465089D03*
X281590Y457489D03*
Y465089D03*
X944500Y1122200D03*
Y1129800D03*
X952500Y1122200D03*
Y1129800D03*
X960500Y1122200D03*
Y1129800D03*
X1697359Y439907D03*
Y447507D03*
X1689359Y439907D03*
Y447507D03*
X1681359Y439907D03*
Y447507D03*
X1816338Y460823D03*
Y468423D03*
X1771763Y874225D03*
Y881825D03*
X1763763Y874225D03*
Y881825D03*
X1755763Y874225D03*
Y881825D03*
X1831598Y460827D03*
Y468427D03*
X1823987Y460819D03*
Y468419D03*
X1890763Y895225D03*
Y902825D03*
X1906763Y895225D03*
Y902825D03*
X1898763Y895225D03*
Y902825D03*
G54D71*
X995631Y1112483D03*
Y1110515D03*
X1007743D03*
Y1112483D03*
G54D62*
X1024793Y1118601D03*
G54D17*
X98063Y908025D03*
X195890Y470289D03*
X516346Y1442322D03*
X1738659Y473707D03*
X1813063Y908025D03*
G54D53*
X862205Y277953D03*
X848032D03*
X833859D03*
X862205Y272441D03*
X848032D03*
X833859D03*
X862205Y263779D03*
X848032D03*
X833859D03*
X862205Y258268D03*
X848032D03*
X833859D03*
X862205Y282283D03*
X848032D03*
X833859D03*
X862205Y268110D03*
X848032D03*
X833859D03*
X862205Y253937D03*
X848032D03*
X833859D03*
X855118Y282677D03*
X840945D03*
X826772D03*
X855118Y277165D03*
X840945D03*
X826772D03*
X855118Y272835D03*
X840945D03*
X826772D03*
X855118Y268504D03*
X840945D03*
X826772D03*
X855118Y262992D03*
X840945D03*
X826772D03*
X862205Y306299D03*
X848032D03*
X833859D03*
X862205Y300787D03*
X848032D03*
X833859D03*
X862205Y292126D03*
X848032D03*
X833859D03*
X862205Y286614D03*
X848032D03*
X833859D03*
X862205Y310630D03*
X848032D03*
X833859D03*
X862205Y296457D03*
X848032D03*
X833859D03*
X855118Y311023D03*
X840945D03*
X826772D03*
X855118Y305512D03*
X840945D03*
X826772D03*
X855118Y296850D03*
X840945D03*
X826772D03*
X855118Y291338D03*
X840945D03*
X826772D03*
X855118Y315354D03*
X840945D03*
X826772D03*
X855118Y301181D03*
X840945D03*
X826772D03*
X855118Y287008D03*
X840945D03*
X826772D03*
X904725Y272835D03*
Y277165D03*
Y282677D03*
X911811Y272441D03*
Y277953D03*
Y282283D03*
X904725Y262992D03*
Y268504D03*
X911811Y253937D03*
Y258268D03*
Y263779D03*
Y268110D03*
X897638Y282283D03*
Y272441D03*
Y277953D03*
Y253937D03*
Y268110D03*
Y258268D03*
Y263779D03*
X890552Y272835D03*
Y277165D03*
Y282677D03*
Y262992D03*
Y268504D03*
X876378Y277953D03*
Y272441D03*
Y263779D03*
Y258268D03*
Y282283D03*
Y268110D03*
Y253937D03*
X869292Y282677D03*
Y277165D03*
Y272835D03*
Y268504D03*
Y262992D03*
X904725Y305512D03*
Y311023D03*
Y315354D03*
X911811Y306299D03*
Y310630D03*
X904725Y301181D03*
X911811Y300787D03*
X904725Y287008D03*
Y291338D03*
Y296850D03*
X911811Y286614D03*
Y292126D03*
Y296457D03*
X897638Y310630D03*
Y306299D03*
Y296457D03*
Y286614D03*
Y292126D03*
Y300787D03*
X890552Y315354D03*
Y305512D03*
Y311023D03*
Y287008D03*
Y301181D03*
Y291338D03*
Y296850D03*
X876378Y306299D03*
Y300787D03*
Y292126D03*
Y286614D03*
Y310630D03*
Y296457D03*
X869292Y311023D03*
Y305512D03*
Y296850D03*
Y291338D03*
Y315354D03*
Y301181D03*
Y287008D03*
X1091089Y520057D03*
X1095420D03*
X1100932D03*
X1105262D03*
X1109593D03*
X1115105D03*
X1119435D03*
X1123766D03*
X1129278D03*
X1133609D03*
X1095026Y527143D03*
X1099357D03*
X1104869D03*
X1109199D03*
X1113530D03*
X1119042D03*
X1123372D03*
X1127703D03*
X1133215D03*
X1091089Y534230D03*
X1095420D03*
X1100932D03*
X1105262D03*
X1109593D03*
X1115105D03*
X1119435D03*
X1123766D03*
X1129278D03*
X1133609D03*
X1095026Y541317D03*
X1099357D03*
X1104869D03*
X1109199D03*
X1113530D03*
X1119042D03*
X1123372D03*
X1127703D03*
X1133215D03*
X1091089Y548403D03*
X1095420D03*
X1100932D03*
X1105262D03*
X1109593D03*
X1115105D03*
X1119435D03*
X1123766D03*
X1129278D03*
X1133609D03*
X1095026Y555490D03*
X1099357D03*
X1104869D03*
X1109199D03*
X1113530D03*
X1119042D03*
X1123372D03*
X1127703D03*
X1133215D03*
X1091089Y562576D03*
X1095420D03*
X1100932D03*
X1105262D03*
X1109593D03*
X1115105D03*
X1119435D03*
X1123766D03*
X1129278D03*
X1133609D03*
X1095026Y569663D03*
X1099357D03*
X1104869D03*
X1109199D03*
X1113530D03*
X1119042D03*
X1123372D03*
X1127703D03*
X1133215D03*
X1091089Y691711D03*
Y705884D03*
Y720057D03*
Y734230D03*
Y748403D03*
Y762577D03*
X1095420Y691711D03*
Y705884D03*
Y720057D03*
Y734230D03*
Y748403D03*
Y762577D03*
X1100932Y691711D03*
Y705884D03*
Y720057D03*
Y734230D03*
Y748403D03*
Y762577D03*
X1105262Y691711D03*
Y705884D03*
Y720057D03*
Y734230D03*
Y748403D03*
Y762577D03*
X1109593Y691711D03*
Y705884D03*
Y720057D03*
Y734230D03*
Y748403D03*
Y762577D03*
X1115105Y691711D03*
Y705884D03*
Y720057D03*
Y734230D03*
Y748403D03*
Y762577D03*
X1119435Y691711D03*
Y705884D03*
Y720057D03*
Y734230D03*
Y748403D03*
Y762577D03*
X1123766Y691711D03*
Y705884D03*
Y720057D03*
Y734230D03*
Y748403D03*
Y762577D03*
X1129278Y691711D03*
Y705884D03*
Y720057D03*
Y734230D03*
Y748403D03*
Y762577D03*
X1133609Y691711D03*
Y705884D03*
Y720057D03*
Y734230D03*
Y748403D03*
Y762577D03*
X1095026Y698797D03*
Y712970D03*
Y727144D03*
Y741317D03*
Y755490D03*
X1099357Y698797D03*
Y712970D03*
Y727144D03*
Y741317D03*
Y755490D03*
X1104869Y698797D03*
Y712970D03*
Y727144D03*
Y741317D03*
Y755490D03*
X1109199Y698797D03*
Y712970D03*
Y727144D03*
Y741317D03*
Y755490D03*
X1113530Y698797D03*
Y712970D03*
Y727144D03*
Y741317D03*
Y755490D03*
X1119042Y698797D03*
Y712970D03*
Y727144D03*
Y741317D03*
Y755490D03*
X1123372Y698797D03*
Y712970D03*
Y727144D03*
Y741317D03*
Y755490D03*
X1127703Y698797D03*
Y712970D03*
Y727144D03*
Y741317D03*
Y755490D03*
X1133215Y698797D03*
Y712970D03*
Y727144D03*
Y741317D03*
Y755490D03*
X1091089Y776750D03*
Y790923D03*
Y805096D03*
Y819270D03*
Y833443D03*
Y847616D03*
X1095420Y776750D03*
Y790923D03*
Y805096D03*
Y819270D03*
Y833443D03*
Y847616D03*
X1100932Y776750D03*
Y790923D03*
Y805096D03*
Y819270D03*
Y833443D03*
Y847616D03*
X1105262Y776750D03*
Y790923D03*
Y805096D03*
Y819270D03*
Y833443D03*
Y847616D03*
X1109593Y776750D03*
Y790923D03*
Y805096D03*
Y819270D03*
Y833443D03*
Y847616D03*
X1115105Y776750D03*
Y790923D03*
Y805096D03*
Y819270D03*
Y833443D03*
Y847616D03*
X1119435Y776750D03*
Y790923D03*
Y805096D03*
Y819270D03*
Y833443D03*
Y847616D03*
X1123766Y776750D03*
Y790923D03*
Y805096D03*
Y819270D03*
Y833443D03*
Y847616D03*
X1129278Y776750D03*
Y790923D03*
Y805096D03*
Y819270D03*
Y833443D03*
Y847616D03*
X1133609Y776750D03*
Y790923D03*
Y805096D03*
Y819270D03*
Y833443D03*
Y847616D03*
X1095026Y769663D03*
Y783836D03*
Y798010D03*
Y812183D03*
Y826356D03*
Y840529D03*
Y854703D03*
X1099357Y769663D03*
Y783836D03*
Y798010D03*
Y812183D03*
Y826356D03*
Y840529D03*
Y854703D03*
X1104869Y769663D03*
Y783836D03*
Y798010D03*
Y812183D03*
Y826356D03*
Y840529D03*
Y854703D03*
X1109199Y769663D03*
Y783836D03*
Y798010D03*
Y812183D03*
Y826356D03*
Y840529D03*
Y854703D03*
X1113530Y769663D03*
Y783836D03*
Y798010D03*
Y812183D03*
Y826356D03*
Y840529D03*
Y854703D03*
X1119042Y769663D03*
Y783836D03*
Y798010D03*
Y812183D03*
Y826356D03*
Y840529D03*
Y854703D03*
X1123372Y769663D03*
Y783836D03*
Y798010D03*
Y812183D03*
Y826356D03*
Y840529D03*
Y854703D03*
X1127703Y769663D03*
Y783836D03*
Y798010D03*
Y812183D03*
Y826356D03*
Y840529D03*
Y854703D03*
X1133215Y769663D03*
Y783836D03*
Y798010D03*
Y812183D03*
Y826356D03*
Y840529D03*
Y854703D03*
X1091089Y861789D03*
Y875962D03*
Y890136D03*
Y904309D03*
Y918482D03*
Y932655D03*
X1095420Y861789D03*
Y875962D03*
Y890136D03*
Y904309D03*
Y918482D03*
Y932655D03*
X1100932Y861789D03*
Y875962D03*
Y890136D03*
Y904309D03*
Y918482D03*
Y932655D03*
X1105262Y861789D03*
Y875962D03*
Y890136D03*
Y904309D03*
Y918482D03*
Y932655D03*
X1109593Y861789D03*
Y875962D03*
Y890136D03*
Y904309D03*
Y918482D03*
Y932655D03*
X1115105Y861789D03*
Y875962D03*
Y890136D03*
Y904309D03*
Y918482D03*
Y932655D03*
X1119435Y861789D03*
Y875962D03*
Y890136D03*
Y904309D03*
Y918482D03*
Y932655D03*
X1123766Y861789D03*
Y875962D03*
Y890136D03*
Y904309D03*
Y918482D03*
Y932655D03*
X1129278Y861789D03*
Y875962D03*
Y890136D03*
Y904309D03*
Y918482D03*
Y932655D03*
X1133609Y861789D03*
Y875962D03*
Y890136D03*
Y904309D03*
Y918482D03*
Y932655D03*
X1095026Y868876D03*
Y883049D03*
Y897222D03*
Y911396D03*
Y925569D03*
Y939742D03*
X1099357Y868876D03*
Y883049D03*
Y897222D03*
Y911396D03*
Y925569D03*
Y939742D03*
X1104869Y868876D03*
Y883049D03*
Y897222D03*
Y911396D03*
Y925569D03*
Y939742D03*
X1109199Y868876D03*
Y883049D03*
Y897222D03*
Y911396D03*
Y925569D03*
Y939742D03*
X1113530Y868876D03*
Y883049D03*
Y897222D03*
Y911396D03*
Y925569D03*
Y939742D03*
X1119042Y868876D03*
Y883049D03*
Y897222D03*
Y911396D03*
Y925569D03*
Y939742D03*
X1123372Y868876D03*
Y883049D03*
Y897222D03*
Y911396D03*
Y925569D03*
Y939742D03*
X1127703Y868876D03*
Y883049D03*
Y897222D03*
Y911396D03*
Y925569D03*
Y939742D03*
X1133215Y868876D03*
Y883049D03*
Y897222D03*
Y911396D03*
Y925569D03*
Y939742D03*
G54D44*
X197263Y898775D03*
Y898275D03*
X295090Y461039D03*
Y460539D03*
X965500Y1125250D03*
Y1124750D03*
X1836637Y464577D03*
Y464077D03*
X1912263Y898775D03*
Y898275D03*
G54D72*
G01X94643Y889437D02*
X101120D01*
X102207Y890524D01*
G01X75357Y889437D02*
X71936D01*
X71348Y890025D01*
X70263D01*
X68763Y891525D01*
X67063D01*
X64563Y894025D01*
G01X192470Y451701D02*
X198782D01*
X200022Y452941D01*
G01X173184Y451701D02*
X169763D01*
X169400Y452064D01*
X168745D01*
X167020Y453789D01*
X164890D01*
X162390Y456289D01*
G01X1002671Y1117555D02*
Y1124700D01*
G01X1715953Y455119D02*
X1712559D01*
X1711596Y456082D01*
X1708784D01*
X1705159Y459707D01*
G01X1735239Y455119D02*
X1741600D01*
X1742540Y456059D01*
X1742758D01*
G01X1809643Y889437D02*
X1817418D01*
X1817739Y889758D01*
G01X1790357Y889437D02*
X1786936D01*
X1786348Y890025D01*
X1785263D01*
X1783763Y891525D01*
X1782063D01*
X1779563Y894025D01*
G54D36*
X131200Y262981D03*
Y715737D03*
Y1168492D03*
X379232Y262981D03*
Y715737D03*
Y1168492D03*
X627263Y262981D03*
Y715737D03*
Y1168492D03*
X747244Y381878D03*
Y814949D03*
X961417Y703925D03*
Y972429D03*
X1181889Y381878D03*
Y972429D03*
X1301870Y262980D03*
Y715737D03*
Y1168492D03*
X1549901Y262981D03*
Y715737D03*
Y1168492D03*
X1797933Y262980D03*
Y715737D03*
Y1168492D03*
G54D27*
X64563Y894025D03*
X56963D03*
X32463Y866525D03*
X40063D03*
X162390Y456289D03*
X154790D03*
X133290Y429089D03*
X140890D03*
X711500Y1463600D03*
X719100D03*
X817800Y1333000D03*
X810200D03*
X817800Y1296000D03*
X810200D03*
X817800Y1371500D03*
X810200D03*
X951461Y1093799D03*
X943861D03*
X951300Y1101700D03*
X943700D03*
X951400Y1109600D03*
X943800D03*
X994800Y1136500D03*
X987200D03*
X994800Y1144500D03*
X987200D03*
X960200Y1082500D03*
X967800D03*
X1705159Y459707D03*
X1697559D03*
X1673059Y432207D03*
X1680659D03*
X1779563Y894025D03*
X1771963D03*
X1747463Y866525D03*
X1755063D03*
G54D18*
X88941Y905416D03*
X186768Y467680D03*
X121736Y903674D03*
X219563Y465938D03*
X512849Y1438455D03*
X974200Y1130000D03*
X1762332Y469356D03*
X1729537Y471098D03*
X1803941Y905416D03*
X1836736Y903674D03*
G54D45*
X384055Y1330472D03*
Y1320472D03*
X354055Y1330472D03*
X364055D03*
X354055Y1320472D03*
X364055D03*
X324055Y1330472D03*
X334055D03*
X324055Y1320472D03*
X334055D03*
X304055Y1330472D03*
Y1320472D03*
X294055Y1330472D03*
Y1320472D03*
X384055Y1340472D03*
Y1350472D03*
X354055Y1340472D03*
Y1350472D03*
X364055Y1340472D03*
Y1350472D03*
X324055Y1340472D03*
Y1350472D03*
X334055Y1340472D03*
Y1350472D03*
X304055D03*
Y1340472D03*
X294055Y1350472D03*
Y1340472D03*
X474055Y1330472D03*
X484055D03*
X474055Y1320472D03*
X484055D03*
X444055Y1330472D03*
X454055D03*
X444055Y1320472D03*
X454055D03*
X414055Y1330472D03*
X424055D03*
X414055Y1320472D03*
X424055D03*
X394055Y1330472D03*
Y1320472D03*
X474055Y1340472D03*
Y1350472D03*
X484055Y1340472D03*
Y1350472D03*
X444055Y1340472D03*
Y1350472D03*
X454055Y1340472D03*
Y1350472D03*
X414055Y1340472D03*
Y1350472D03*
X424055Y1340472D03*
Y1350472D03*
X394055Y1340472D03*
Y1350472D03*
G54D54*
X855100Y258531D03*
X841000D03*
X826700D03*
X869300D03*
X1137600Y527100D03*
X1137446Y541317D03*
Y555490D03*
Y569663D03*
Y698798D03*
Y712971D03*
Y727144D03*
Y741317D03*
Y755490D03*
Y769663D03*
Y783836D03*
Y798010D03*
Y812183D03*
Y826356D03*
Y840529D03*
Y854703D03*
Y868876D03*
Y883049D03*
Y897222D03*
Y911396D03*
Y925569D03*
Y939742D03*
G54D63*
X1031000Y1099500D03*
G54D73*
G01X1027600Y1405400D02*
X1018200Y1414800D01*
Y1440700D01*
X1007600Y1451300D01*
X993200D01*
G54D28*
X83163Y904975D03*
X180990Y467239D03*
X1024284Y1102936D03*
X1723759Y470657D03*
X1798163Y904975D03*
G54D37*
X161800Y853585D03*
Y878385D03*
Y917685D03*
Y892885D03*
X259627Y416249D03*
Y441049D03*
Y455549D03*
Y480349D03*
X1802496Y458967D03*
Y419667D03*
Y444467D03*
Y483767D03*
X1876600Y854185D03*
Y918285D03*
Y893485D03*
Y878985D03*
G54D55*
X859086Y1290016D03*
Y1300984D03*
X842500Y1404984D03*
Y1394016D03*
X860000Y1404984D03*
Y1394016D03*
X871589Y1290016D03*
Y1300984D03*
X884060Y1290048D03*
Y1301016D03*
X876500Y1404984D03*
Y1394016D03*
G54D19*
X88941Y902016D03*
X186768Y464280D03*
X121736Y900274D03*
X219563Y462538D03*
X512849Y1435055D03*
X974200Y1126600D03*
X1762332Y465956D03*
X1729537Y467698D03*
X1803941Y902016D03*
X1836736Y900274D03*
G54D64*
X1021216Y1137521D03*
G54D46*
X462000Y1382985D03*
Y1372985D03*
Y1362985D03*
X474000Y1382985D03*
Y1372985D03*
Y1362985D03*
X426000D03*
X450000Y1372985D03*
Y1382985D03*
X414000Y1372985D03*
X450000Y1362985D03*
X438000Y1372985D03*
X414000Y1362985D03*
X438000D03*
X426000Y1372985D03*
X438000Y1382985D03*
X414000D03*
X426000D03*
X498000Y1332985D03*
X510000Y1344485D03*
X498000Y1352985D03*
X522000Y1344485D03*
X498000Y1342985D03*
X510000Y1354485D03*
X522000D03*
X510000Y1364485D03*
X522000D03*
X510000Y1374485D03*
Y1384485D03*
X522000Y1374485D03*
Y1384485D03*
X498000Y1382985D03*
Y1372985D03*
X486000Y1382985D03*
Y1372985D03*
X498000Y1362985D03*
X486000D03*
X658200Y1329200D03*
X666100D03*
X581800Y1321200D03*
Y1329100D03*
X589700D03*
Y1321200D03*
X594800Y1313500D03*
X597600Y1321200D03*
Y1329100D03*
X610600Y1313500D03*
Y1305600D03*
Y1297600D03*
X602700Y1313500D03*
Y1305600D03*
Y1297600D03*
X629200Y1329100D03*
X605500Y1321200D03*
X613400D03*
X605500Y1329100D03*
X613400D03*
X621300D03*
X666100Y1360800D03*
Y1368700D03*
Y1376600D03*
Y1352900D03*
X658200Y1360800D03*
Y1368700D03*
Y1376600D03*
Y1352900D03*
X666100Y1337100D03*
Y1345000D03*
X658200Y1337100D03*
Y1345000D03*
X581800Y1376500D03*
Y1384400D03*
Y1392300D03*
Y1360700D03*
Y1368600D03*
Y1352800D03*
Y1344900D03*
Y1337000D03*
X589700Y1392300D03*
Y1400200D03*
Y1344900D03*
Y1352800D03*
Y1384400D03*
Y1376500D03*
Y1368600D03*
Y1360700D03*
Y1337000D03*
X597600Y1400200D03*
Y1408100D03*
Y1360700D03*
Y1368600D03*
Y1392300D03*
Y1376500D03*
Y1384400D03*
Y1352800D03*
Y1337000D03*
Y1344900D03*
X629200D03*
X621300D03*
X613400D03*
X605500D03*
Y1360700D03*
X613400D03*
X621300D03*
X629200D03*
X605500Y1352800D03*
X613400D03*
X621300D03*
X629200D03*
Y1368600D03*
Y1376500D03*
X605500Y1408100D03*
Y1400200D03*
Y1392300D03*
Y1384400D03*
Y1376500D03*
Y1368600D03*
X613400Y1400200D03*
Y1392300D03*
Y1384400D03*
Y1376500D03*
Y1368600D03*
X621300Y1376500D03*
Y1368600D03*
X629200Y1337000D03*
X613400D03*
X621300D03*
X605500D03*
X613400Y1408100D03*
X705600Y1329200D03*
X697700Y1321300D03*
Y1329200D03*
X689800D03*
Y1321300D03*
X693800Y1313900D03*
Y1306000D03*
X685900D03*
X678000D03*
Y1313900D03*
X685900D03*
X681900Y1321300D03*
X674000D03*
Y1329200D03*
X681900D03*
X693800Y1298000D03*
X685900D03*
X678000D03*
X768867Y1311110D03*
Y1335110D03*
Y1327110D03*
Y1319110D03*
X705600Y1337100D03*
Y1360800D03*
Y1352900D03*
Y1345000D03*
Y1376600D03*
Y1368700D03*
X699600Y1408200D03*
Y1392400D03*
Y1400300D03*
X697700Y1345000D03*
Y1360800D03*
Y1368700D03*
Y1376600D03*
X697100Y1384600D03*
X697700Y1352900D03*
Y1337100D03*
X691700Y1408200D03*
Y1400300D03*
X675900D03*
X683800D03*
Y1408200D03*
X675900D03*
X689800Y1352900D03*
Y1384500D03*
Y1376600D03*
X691700Y1392400D03*
X689800Y1368700D03*
Y1360800D03*
X674000D03*
X681900D03*
Y1368700D03*
X674000D03*
X675900Y1392400D03*
X683800D03*
X674000Y1376600D03*
X681900D03*
Y1384500D03*
X674000D03*
Y1352900D03*
X681900D03*
X689800Y1345000D03*
Y1337100D03*
X681900D03*
X674000D03*
X681900Y1345000D03*
X674000D03*
X768867Y1383110D03*
Y1359110D03*
Y1367110D03*
Y1351110D03*
Y1343110D03*
Y1391110D03*
Y1399110D03*
Y1375110D03*
X786200Y1334100D03*
X794200D03*
X801000Y1333800D03*
X786200Y1326100D03*
X794200D03*
X776867Y1311110D03*
Y1335110D03*
Y1327110D03*
Y1319110D03*
X775600Y1302400D03*
X801000Y1325800D03*
X790056Y1297863D03*
X798056D03*
X782056D03*
X834000Y1324500D03*
Y1317500D03*
Y1310500D03*
Y1303500D03*
X827000D03*
X820000D03*
X827000Y1310500D03*
X820000D03*
X827000Y1317500D03*
X820000D03*
X827000Y1324500D03*
X820000D03*
X776867Y1399110D03*
X790330Y1407929D03*
X782330D03*
X798330D03*
X795000Y1377900D03*
X786600Y1378100D03*
X790950Y1372703D03*
X776867Y1383110D03*
Y1359110D03*
X782950Y1372703D03*
X776867Y1367110D03*
Y1375110D03*
X798950Y1372703D03*
X776867Y1391110D03*
X790223Y1339930D03*
X782223Y1339430D03*
X798223Y1339930D03*
X776867Y1351110D03*
Y1343110D03*
X834000Y1386000D03*
Y1379000D03*
Y1363000D03*
Y1356000D03*
Y1349000D03*
Y1342000D03*
X827000D03*
X820000D03*
X827000Y1349000D03*
X820000D03*
X827000Y1356000D03*
X820000D03*
X827000Y1363000D03*
X820000D03*
X827000Y1379000D03*
X820000D03*
X827000Y1386000D03*
X820000D03*
X827000Y1393000D03*
X820000D03*
X958200Y1303900D03*
X942400D03*
X950300D03*
X934500D03*
X926600D03*
X958200Y1311800D03*
X926600D03*
X934500D03*
X950300D03*
X942400D03*
X903500Y1319400D03*
X950300Y1319700D03*
X958200D03*
X934500D03*
X942400D03*
X926600D03*
X918700D03*
X910800D03*
X887800Y1327100D03*
X934700Y1327500D03*
X895200D03*
X903100D03*
X911000D03*
X926800D03*
X918900D03*
X887800Y1335000D03*
X886400Y1368100D03*
Y1376000D03*
X894300D03*
Y1368100D03*
X934700Y1335400D03*
X926800D03*
X918900D03*
X895200D03*
X903100D03*
X911000D03*
X890400Y1358900D03*
X887800Y1350800D03*
Y1342900D03*
X937300Y1359300D03*
X934700Y1343300D03*
Y1351200D03*
X926800Y1343300D03*
Y1351200D03*
X929400Y1359300D03*
X918900Y1343300D03*
Y1351200D03*
X921500Y1359300D03*
X918000Y1368100D03*
Y1376000D03*
X910100Y1368100D03*
Y1376000D03*
X911000Y1343300D03*
Y1351200D03*
X913600Y1359300D03*
X903100Y1343300D03*
Y1351200D03*
X905700Y1359300D03*
X902200Y1376000D03*
Y1368100D03*
X897800Y1359300D03*
X895200Y1351200D03*
Y1343300D03*
X998600Y1300900D03*
X991500Y1312100D03*
X1020800Y1300400D03*
X991455Y1320416D03*
X996400Y1315900D03*
X996200Y1307800D03*
X1014000Y1300600D03*
X991755Y1327716D03*
X996055Y1324116D03*
X1007100Y1301100D03*
X1011100Y1305300D03*
X1019829Y1306139D03*
X1002700Y1305700D03*
X991800Y1303400D03*
X1000200Y1311700D03*
Y1320500D03*
X1016429Y1333939D03*
X1021829D03*
X1011029D03*
X1005629D03*
X986755Y1323816D03*
X986700Y1307600D03*
X1000200Y1328100D03*
X1050818Y1311189D03*
Y1316589D03*
X1045418Y1321989D03*
X1050818D03*
X1034618Y1311189D03*
X1040018D03*
X1045418D03*
X1040018Y1316589D03*
X1034618D03*
X1040018Y1321989D03*
X1031600Y1335100D03*
X1037200Y1335000D03*
X1034618Y1321989D03*
X997900Y1335800D03*
X992500D03*
X997900Y1341200D03*
X992500D03*
X997900Y1346600D03*
X992500D03*
X997900Y1352000D03*
X992500D03*
Y1357400D03*
X997900D03*
X989083Y1387764D03*
X989509Y1393422D03*
X994700Y1385000D03*
X999700Y1374500D03*
X989100Y1381700D03*
X994200Y1362700D03*
X1019829Y1389539D03*
X1013692Y1389688D03*
X1019829Y1361739D03*
X1014306Y1361710D03*
X1008870Y1361681D03*
X1003367Y1361655D03*
X1004217Y1389394D03*
X1008298Y1393071D03*
X994400Y1377300D03*
X999930Y1393070D03*
X999800Y1381600D03*
X999900Y1366800D03*
X994300Y1370100D03*
X989200Y1374800D03*
X988900Y1366900D03*
X1034600Y1349600D03*
X1042400Y1349500D03*
X1037540Y1344964D03*
X1034799Y1340183D03*
X1044700Y1335500D03*
X1043300Y1342500D03*
X1048000Y1346100D03*
X1037111Y1372380D03*
X1039988Y1367352D03*
X1044400Y1363100D03*
X1036900Y1362600D03*
X1034380Y1367469D03*
X1031300Y1362700D03*
X1042100Y1377100D03*
X1034300Y1377200D03*
X1047401Y1375084D03*
X1066481Y1327759D03*
X1061081D03*
X1066481Y1333159D03*
X1061081D03*
X1061618Y1316589D03*
X1056218Y1311189D03*
X1061618D03*
X1056218Y1316589D03*
X1060218Y1321989D03*
X1066491Y1319983D03*
X1066407Y1313972D03*
X1066481Y1338559D03*
X1061081D03*
X1066481Y1343959D03*
X1061081D03*
X1066481Y1376359D03*
Y1349359D03*
Y1354759D03*
Y1360159D03*
Y1365559D03*
Y1370959D03*
X1061081Y1376359D03*
Y1370959D03*
Y1365559D03*
Y1360159D03*
Y1354759D03*
Y1349359D03*
G54D74*
G01X1024284Y1099586D02*
Y1099164D01*
X1021970Y1096850D01*
G54D38*
X125056Y909101D03*
X222883Y471365D03*
X950211Y1087648D03*
X993800Y1131000D03*
X1025500Y1122400D03*
X978300Y1084500D03*
X1765652Y474783D03*
X1840056Y909101D03*
G54D47*
X501699Y1429055D03*
Y1438055D03*
G54D56*
X786631Y1320085D03*
Y1315085D03*
Y1310085D03*
X787101Y1362591D03*
Y1357591D03*
Y1352591D03*
X786880Y1400259D03*
Y1395259D03*
Y1390259D03*
G54D65*
X1021216Y1143121D03*
G54D29*
X83163Y902475D03*
X180990Y464739D03*
X1024284Y1100436D03*
X1723759Y468157D03*
X1798163Y902475D03*
G54D75*
G01X489037Y-206331D02*
X489911Y-205456D01*
X490566Y-203998D01*
X491003Y-201955D01*
X490566Y-200206D01*
X489693Y-199039D01*
X488164Y-198164D01*
X482269D01*
Y-215664D01*
X489474D01*
X491003Y-214498D01*
X491876Y-212747D01*
X492313Y-210706D01*
X491876Y-208664D01*
X490566Y-206914D01*
X489037Y-206331D01*
X482269D01*
G01X501734Y-215664D02*
Y-203998D01*
G01Y-206331D02*
X502826Y-205164D01*
X503918Y-204289D01*
X505446Y-203998D01*
X506537Y-204289D01*
X507848Y-205164D01*
G01X517706Y-220914D02*
X519016Y-221497D01*
X520763Y-220914D01*
X521854Y-219748D01*
X522728Y-218289D01*
X524037Y-213623D01*
X526876Y-203998D01*
G01X519889D02*
X524037Y-213623D01*
G01X543284Y-205456D02*
X541756Y-204289D01*
X540446Y-203998D01*
X538699Y-204581D01*
X537389Y-205747D01*
X536516Y-207789D01*
X536297Y-209831D01*
X536516Y-211873D01*
X537389Y-213623D01*
X538699Y-215081D01*
X540446Y-215664D01*
X541974Y-215081D01*
X543284Y-213914D01*
G01X554016Y-207789D02*
X561003D01*
X560348Y-205747D01*
X559256Y-204581D01*
X557728Y-203998D01*
X556199Y-204289D01*
X554889Y-205164D01*
X554016Y-207206D01*
X553579Y-208956D01*
Y-210706D01*
X554016Y-212456D01*
X555108Y-214206D01*
X556418Y-215372D01*
X557946Y-215664D01*
X559474Y-215081D01*
X561003Y-213331D01*
G01X597094Y-199623D02*
X595784Y-198747D01*
X594256Y-198164D01*
X592509D01*
X590544Y-199039D01*
X589016Y-200497D01*
X587924Y-202248D01*
X587051Y-205164D01*
X586832Y-207789D01*
X587269Y-210414D01*
X587924Y-212164D01*
X589234Y-213914D01*
X590763Y-215081D01*
X592291Y-215664D01*
X593819D01*
X595348Y-215081D01*
X596658Y-214206D01*
X597750Y-213040D01*
G01X613721Y-215664D02*
Y-203998D01*
G01Y-206039D02*
X612848Y-204873D01*
X611537Y-204289D01*
X610009Y-203998D01*
X608481Y-204581D01*
X607171Y-205747D01*
X606297Y-207497D01*
X605861Y-209831D01*
X606297Y-212164D01*
X607171Y-213914D01*
X608481Y-215081D01*
X610009Y-215664D01*
X611537Y-215372D01*
X612848Y-214498D01*
X613721Y-213331D01*
G01X623579Y-215664D02*
Y-203998D01*
G01Y-206914D02*
X624453Y-205456D01*
X625763Y-204289D01*
X627509Y-203998D01*
X629037Y-204289D01*
X630348Y-205456D01*
X631003Y-207497D01*
Y-215664D01*
G01X640206Y-220914D02*
X641516Y-221497D01*
X643263Y-220914D01*
X644354Y-219748D01*
X645228Y-218289D01*
X646537Y-213623D01*
X649376Y-203998D01*
G01X642389D02*
X646537Y-213623D01*
G01X662291Y-215664D02*
X660981Y-215372D01*
X659671Y-214206D01*
X658797Y-212164D01*
X658361Y-209831D01*
X658797Y-207497D01*
X659671Y-205456D01*
X660981Y-204289D01*
X662291Y-203998D01*
X663601Y-204289D01*
X664911Y-205456D01*
X665784Y-207497D01*
X666003Y-209831D01*
X665784Y-212164D01*
X664911Y-214206D01*
X663601Y-215372D01*
X662291Y-215664D01*
G01X676079D02*
Y-203998D01*
G01Y-206914D02*
X676953Y-205456D01*
X678263Y-204289D01*
X680009Y-203998D01*
X681537Y-204289D01*
X682848Y-205456D01*
X683503Y-207497D01*
Y-215664D01*
G01X710424D02*
Y-198164D01*
X715883D01*
X717629Y-199039D01*
X718721Y-200206D01*
X719158Y-202539D01*
X718721Y-204873D01*
X717411Y-206331D01*
X715883Y-207206D01*
X710424D01*
G01X715883D02*
X719158Y-215664D01*
G01X732291Y-216247D02*
X731854Y-215956D01*
Y-215372D01*
X732291Y-215081D01*
X732728Y-215372D01*
Y-215956D01*
X732291Y-216247D01*
G01X744988Y-215664D02*
Y-198164D01*
X749354D01*
X751101Y-199039D01*
X752411Y-200206D01*
X753503Y-201955D01*
X754376Y-203998D01*
X754594Y-206914D01*
X754376Y-209831D01*
X753503Y-211873D01*
X752411Y-213623D01*
X751101Y-214789D01*
X749354Y-215664D01*
X744988D01*
G01X762924D02*
Y-198164D01*
X768164D01*
X769911Y-199039D01*
X771221Y-201081D01*
X771658Y-203414D01*
X771221Y-205747D01*
X770129Y-207497D01*
X768164Y-208373D01*
X762924D01*
G01X786537Y-206331D02*
X787411Y-205456D01*
X788066Y-203998D01*
X788503Y-201955D01*
X788066Y-200206D01*
X787193Y-199039D01*
X785664Y-198164D01*
X779769D01*
Y-215664D01*
X786974D01*
X788503Y-214498D01*
X789376Y-212747D01*
X789813Y-210706D01*
X789376Y-208664D01*
X788066Y-206914D01*
X786537Y-206331D01*
X779769D01*
G01X595364Y-170664D02*
Y-153164D01*
X601041Y-167747D01*
X606718Y-153164D01*
Y-170664D01*
G01X618541D02*
X617231Y-170372D01*
X615921Y-169206D01*
X615047Y-167164D01*
X614611Y-164831D01*
X615047Y-162497D01*
X615921Y-160456D01*
X617231Y-159289D01*
X618541Y-158998D01*
X619851Y-159289D01*
X621161Y-160456D01*
X622034Y-162497D01*
X622253Y-164831D01*
X622034Y-167164D01*
X621161Y-169206D01*
X619851Y-170372D01*
X618541Y-170664D01*
G01X639971Y-153164D02*
Y-170664D01*
G01Y-168040D02*
X639098Y-169498D01*
X637787Y-170372D01*
X636259Y-170664D01*
X634513Y-170081D01*
X633203Y-168623D01*
X632329Y-166873D01*
X632111Y-164831D01*
X632329Y-162789D01*
X633203Y-161039D01*
X634513Y-159581D01*
X636259Y-158998D01*
X637787Y-159289D01*
X638879Y-159873D01*
X639971Y-161039D01*
G01X650266Y-162789D02*
X657253D01*
X656598Y-160747D01*
X655506Y-159581D01*
X653978Y-158998D01*
X652449Y-159289D01*
X651139Y-160164D01*
X650266Y-162206D01*
X649829Y-163956D01*
Y-165706D01*
X650266Y-167456D01*
X651358Y-169206D01*
X652668Y-170372D01*
X654196Y-170664D01*
X655724Y-170081D01*
X657253Y-168331D01*
G01X671041Y-170664D02*
Y-153164D01*
G01X839441Y-215664D02*
Y-198164D01*
X836821Y-201664D01*
G01Y-215664D02*
X842061D01*
G01X852793Y-208373D02*
X854321Y-206331D01*
X855631Y-205164D01*
X857378Y-204581D01*
X858906Y-205164D01*
X859998Y-206331D01*
X860871Y-208081D01*
X861089Y-210122D01*
X860871Y-211873D01*
X859998Y-213623D01*
X858687Y-215081D01*
X857159Y-215664D01*
X855413Y-215081D01*
X853884Y-213331D01*
X853011Y-210706D01*
X852793Y-207789D01*
X853229Y-203998D01*
X853884Y-201955D01*
X854976Y-199914D01*
X856504Y-198456D01*
X858033Y-198164D01*
X859561Y-198747D01*
X860653Y-200206D01*
G01X869638Y-212164D02*
X870947Y-214206D01*
X872694Y-215372D01*
X874659Y-215664D01*
X876406Y-215372D01*
X878153Y-213914D01*
X879244Y-212164D01*
X879463Y-210414D01*
X879026Y-208373D01*
X877498Y-206914D01*
X875969Y-206331D01*
X874004D01*
G01X875969D02*
X877279Y-205456D01*
X878371Y-203998D01*
X878808Y-202248D01*
X878371Y-200497D01*
X877279Y-199039D01*
X875314Y-198164D01*
X873349Y-198456D01*
X871384Y-199623D01*
G01X891941Y-215664D02*
Y-198164D01*
X889321Y-201664D01*
G01Y-215664D02*
X894561D01*
G01X909004D02*
X909441Y-211873D01*
X910096Y-208664D01*
X910969Y-205747D01*
X912061Y-202539D01*
X913808Y-198164D01*
X905074D01*
G01X826324Y-170664D02*
Y-153164D01*
X831564D01*
X833311Y-154039D01*
X834621Y-156081D01*
X835058Y-158414D01*
X834621Y-160747D01*
X833529Y-162497D01*
X831564Y-163373D01*
X826324D01*
G01X852994Y-154623D02*
X851684Y-153747D01*
X850156Y-153164D01*
X848409D01*
X846444Y-154039D01*
X844916Y-155497D01*
X843824Y-157248D01*
X842951Y-160164D01*
X842732Y-162789D01*
X843169Y-165414D01*
X843824Y-167164D01*
X845134Y-168914D01*
X846663Y-170081D01*
X848191Y-170664D01*
X849719D01*
X851248Y-170081D01*
X852558Y-169206D01*
X853650Y-168040D01*
G01X867437Y-161331D02*
X868311Y-160456D01*
X868966Y-158998D01*
X869403Y-156955D01*
X868966Y-155206D01*
X868093Y-154039D01*
X866564Y-153164D01*
X860669D01*
Y-170664D01*
X867874D01*
X869403Y-169498D01*
X870276Y-167747D01*
X870713Y-165706D01*
X870276Y-163664D01*
X868966Y-161914D01*
X867437Y-161331D01*
X860669D01*
G01X876641Y-176497D02*
X889741D01*
G01X895669Y-170664D02*
Y-153164D01*
X905713Y-170664D01*
Y-153164D01*
G01X918191Y-170664D02*
X916444Y-170372D01*
X914916Y-169206D01*
X913606Y-167456D01*
X912732Y-165414D01*
X912296Y-163081D01*
Y-160747D01*
X912732Y-158414D01*
X913606Y-156372D01*
X914916Y-154623D01*
X916444Y-153456D01*
X918191Y-153164D01*
X919937Y-153456D01*
X921466Y-154623D01*
X922776Y-156372D01*
X923650Y-158414D01*
X924086Y-160747D01*
Y-163081D01*
X923650Y-165414D01*
X922776Y-167456D01*
X921466Y-169206D01*
X919937Y-170372D01*
X918191Y-170664D01*
G01X1000741Y-215664D02*
Y-198164D01*
X998121Y-201664D01*
G01Y-215664D02*
X1003361D01*
G01X969032Y-153164D02*
X974491Y-170664D01*
X979950Y-153164D01*
G01X996358Y-170664D02*
X987624D01*
Y-153164D01*
X996358D01*
G01X992864Y-161622D02*
X987624D01*
G01X1005124Y-170664D02*
Y-153164D01*
X1010583D01*
X1012329Y-154039D01*
X1013421Y-155206D01*
X1013858Y-157539D01*
X1013421Y-159873D01*
X1012111Y-161331D01*
X1010583Y-162206D01*
X1005124D01*
G01X1010583D02*
X1013858Y-170664D01*
G01X1026991Y-171247D02*
X1026554Y-170956D01*
Y-170372D01*
X1026991Y-170081D01*
X1027428Y-170372D01*
Y-170956D01*
X1026991Y-171247D01*
G01X1155058Y-198164D02*
Y-215664D01*
X1146324D01*
G01X1133191D02*
X1131663Y-215372D01*
X1129916Y-214498D01*
X1128824Y-213040D01*
X1128388Y-210997D01*
X1128824Y-208956D01*
X1130134Y-207206D01*
X1132099Y-206331D01*
X1134283D01*
X1135593Y-205747D01*
X1136685Y-204289D01*
X1137121Y-202248D01*
X1136466Y-200206D01*
X1134938Y-198747D01*
X1133191Y-198164D01*
X1131445Y-198747D01*
X1129916Y-200206D01*
X1129261Y-202248D01*
X1129698Y-204289D01*
X1130789Y-205747D01*
X1132099Y-206331D01*
X1134283D01*
X1136248Y-207206D01*
X1137558Y-208956D01*
X1137994Y-210997D01*
X1137558Y-213040D01*
X1136466Y-214498D01*
X1134719Y-215372D01*
X1133191Y-215664D01*
G01X1102574Y-153164D02*
Y-170664D01*
X1111308D01*
G01X1128371D02*
Y-158998D01*
G01Y-161039D02*
X1127498Y-159873D01*
X1126187Y-159289D01*
X1124659Y-158998D01*
X1123131Y-159581D01*
X1121821Y-160747D01*
X1120947Y-162497D01*
X1120511Y-164831D01*
X1120947Y-167164D01*
X1121821Y-168914D01*
X1123131Y-170081D01*
X1124659Y-170664D01*
X1126187Y-170372D01*
X1127498Y-169498D01*
X1128371Y-168331D01*
G01X1137356Y-175914D02*
X1138666Y-176497D01*
X1140413Y-175914D01*
X1141504Y-174748D01*
X1142378Y-173289D01*
X1143687Y-168623D01*
X1146526Y-158998D01*
G01X1139539D02*
X1143687Y-168623D01*
G01X1156166Y-162789D02*
X1163153D01*
X1162498Y-160747D01*
X1161406Y-159581D01*
X1159878Y-158998D01*
X1158349Y-159289D01*
X1157039Y-160164D01*
X1156166Y-162206D01*
X1155729Y-163956D01*
Y-165706D01*
X1156166Y-167456D01*
X1157258Y-169206D01*
X1158568Y-170372D01*
X1160096Y-170664D01*
X1161624Y-170081D01*
X1163153Y-168331D01*
G01X1173884Y-170664D02*
Y-158998D01*
G01Y-161331D02*
X1174976Y-160164D01*
X1176068Y-159289D01*
X1177596Y-158998D01*
X1178687Y-159289D01*
X1179998Y-160164D01*
G01X1244688Y-170664D02*
Y-153164D01*
X1249054D01*
X1250801Y-154039D01*
X1252111Y-155206D01*
X1253203Y-156955D01*
X1254076Y-158998D01*
X1254294Y-161914D01*
X1254076Y-164831D01*
X1253203Y-166873D01*
X1252111Y-168623D01*
X1250801Y-169789D01*
X1249054Y-170664D01*
X1244688D01*
G01X1263716Y-162789D02*
X1270703D01*
X1270048Y-160747D01*
X1268956Y-159581D01*
X1267428Y-158998D01*
X1265899Y-159289D01*
X1264589Y-160164D01*
X1263716Y-162206D01*
X1263279Y-163956D01*
Y-165706D01*
X1263716Y-167456D01*
X1264808Y-169206D01*
X1266118Y-170372D01*
X1267646Y-170664D01*
X1269174Y-170081D01*
X1270703Y-168331D01*
G01X1281216Y-168623D02*
X1282308Y-169789D01*
X1283836Y-170664D01*
X1285146D01*
X1286456Y-170081D01*
X1287329Y-169206D01*
X1287766Y-168040D01*
X1287548Y-166289D01*
X1286674Y-165414D01*
X1282744Y-163664D01*
X1281871Y-161622D01*
X1282308Y-160164D01*
X1283181Y-159289D01*
X1284491Y-158998D01*
X1285801Y-159289D01*
X1287111Y-160164D01*
G01X1301991Y-158998D02*
Y-170664D01*
G01Y-154331D02*
X1301554Y-154039D01*
Y-153456D01*
X1301991Y-153164D01*
X1302428Y-153456D01*
Y-154039D01*
X1301991Y-154331D01*
G01X1316434Y-175039D02*
X1317963Y-176206D01*
X1319709Y-176497D01*
X1321237Y-176206D01*
X1322548Y-174748D01*
X1323421Y-172706D01*
Y-158998D01*
G01Y-161331D02*
X1322548Y-160164D01*
X1321237Y-159289D01*
X1319709Y-158998D01*
X1317963Y-159581D01*
X1316871Y-160747D01*
X1315997Y-162789D01*
X1315561Y-164831D01*
X1315779Y-166581D01*
X1316653Y-168623D01*
X1317963Y-170081D01*
X1319709Y-170664D01*
X1321019Y-170372D01*
X1322548Y-169206D01*
X1323421Y-168040D01*
G01X1333279Y-170664D02*
Y-158998D01*
G01Y-161914D02*
X1334153Y-160456D01*
X1335463Y-159289D01*
X1337209Y-158998D01*
X1338737Y-159289D01*
X1340048Y-160456D01*
X1340703Y-162497D01*
Y-170664D01*
G01X1351216Y-162789D02*
X1358203D01*
X1357548Y-160747D01*
X1356456Y-159581D01*
X1354928Y-158998D01*
X1353399Y-159289D01*
X1352089Y-160164D01*
X1351216Y-162206D01*
X1350779Y-163956D01*
Y-165706D01*
X1351216Y-167456D01*
X1352308Y-169206D01*
X1353618Y-170372D01*
X1355146Y-170664D01*
X1356674Y-170081D01*
X1358203Y-168331D01*
G01X1368934Y-170664D02*
Y-158998D01*
G01Y-161331D02*
X1370026Y-160164D01*
X1371118Y-159289D01*
X1372646Y-158998D01*
X1373737Y-159289D01*
X1375048Y-160164D01*
G01X1266991Y-215664D02*
X1265244Y-215372D01*
X1263716Y-214206D01*
X1262406Y-212456D01*
X1261532Y-210414D01*
X1261096Y-208081D01*
Y-205747D01*
X1261532Y-203414D01*
X1262406Y-201372D01*
X1263716Y-199623D01*
X1265244Y-198456D01*
X1266991Y-198164D01*
X1268737Y-198456D01*
X1270266Y-199623D01*
X1271576Y-201372D01*
X1272450Y-203414D01*
X1272886Y-205747D01*
Y-208081D01*
X1272450Y-210414D01*
X1271576Y-212456D01*
X1270266Y-214206D01*
X1268737Y-215372D01*
X1266991Y-215664D01*
G01X1268737Y-210997D02*
X1271358Y-215664D01*
G01X1279688Y-198164D02*
Y-210706D01*
X1280561Y-213331D01*
X1282308Y-215081D01*
X1284491Y-215664D01*
X1286674Y-215081D01*
X1288421Y-213331D01*
X1289294Y-210706D01*
Y-198164D01*
G01X1299371D02*
X1304611D01*
G01X1301991D02*
Y-215664D01*
G01X1299371D02*
X1304611D01*
G01X1314469D02*
Y-198164D01*
X1324513Y-215664D01*
Y-198164D01*
G01X1341794Y-199623D02*
X1340484Y-198747D01*
X1338956Y-198164D01*
X1337209D01*
X1335244Y-199039D01*
X1333716Y-200497D01*
X1332624Y-202248D01*
X1331751Y-205164D01*
X1331532Y-207789D01*
X1331969Y-210414D01*
X1332624Y-212164D01*
X1333934Y-213914D01*
X1335463Y-215081D01*
X1336991Y-215664D01*
X1338519D01*
X1340048Y-215081D01*
X1341358Y-214206D01*
X1342450Y-213040D01*
G01X1354491Y-215664D02*
Y-207789D01*
X1350124Y-198164D01*
G01X1358858D02*
X1354491Y-207789D01*
G01X1415691Y-198164D02*
X1413944Y-198747D01*
X1412634Y-200206D01*
X1411761Y-201955D01*
X1411106Y-204289D01*
X1410888Y-206914D01*
X1411106Y-209539D01*
X1411761Y-211873D01*
X1412634Y-213623D01*
X1413944Y-215081D01*
X1415691Y-215664D01*
X1417437Y-215081D01*
X1418748Y-213623D01*
X1419621Y-211873D01*
X1420276Y-209539D01*
X1420494Y-206914D01*
X1420276Y-204289D01*
X1419621Y-201955D01*
X1418748Y-200206D01*
X1417437Y-198747D01*
X1415691Y-198164D01*
G01X1429043Y-208373D02*
X1430571Y-206331D01*
X1431881Y-205164D01*
X1433628Y-204581D01*
X1435156Y-205164D01*
X1436248Y-206331D01*
X1437121Y-208081D01*
X1437339Y-210122D01*
X1437121Y-211873D01*
X1436248Y-213623D01*
X1434937Y-215081D01*
X1433409Y-215664D01*
X1431663Y-215081D01*
X1430134Y-213331D01*
X1429261Y-210706D01*
X1429043Y-207789D01*
X1429479Y-203998D01*
X1430134Y-201955D01*
X1431226Y-199914D01*
X1432754Y-198456D01*
X1434283Y-198164D01*
X1435811Y-198747D01*
X1436903Y-200206D01*
G01X1446761Y-216247D02*
X1454621Y-198164D01*
G01X1468191D02*
X1466444Y-198747D01*
X1465134Y-200206D01*
X1464261Y-201955D01*
X1463606Y-204289D01*
X1463388Y-206914D01*
X1463606Y-209539D01*
X1464261Y-211873D01*
X1465134Y-213623D01*
X1466444Y-215081D01*
X1468191Y-215664D01*
X1469937Y-215081D01*
X1471248Y-213623D01*
X1472121Y-211873D01*
X1472776Y-209539D01*
X1472994Y-206914D01*
X1472776Y-204289D01*
X1472121Y-201955D01*
X1471248Y-200206D01*
X1469937Y-198747D01*
X1468191Y-198164D01*
G01X1481979Y-213623D02*
X1483508Y-215081D01*
X1485254Y-215664D01*
X1487001Y-215081D01*
X1488529Y-213331D01*
X1489621Y-210706D01*
X1490058Y-208081D01*
Y-204873D01*
X1489621Y-202248D01*
X1488529Y-199914D01*
X1487219Y-198747D01*
X1485691Y-198164D01*
X1483944Y-198747D01*
X1482634Y-199914D01*
X1481761Y-201664D01*
X1481324Y-203998D01*
X1481761Y-206039D01*
X1482853Y-208081D01*
X1484163Y-209248D01*
X1485691Y-209539D01*
X1487437Y-208956D01*
X1488748Y-207497D01*
X1490058Y-204873D01*
G01X1499261Y-216247D02*
X1507121Y-198164D01*
G01X1516543Y-201081D02*
X1517853Y-199331D01*
X1519381Y-198456D01*
X1521128Y-198164D01*
X1523311Y-198747D01*
X1524839Y-200206D01*
X1525276Y-201955D01*
X1525058Y-203706D01*
X1524184Y-205164D01*
X1519818Y-208081D01*
X1517853Y-210122D01*
X1516543Y-213040D01*
X1516106Y-215664D01*
X1525276D01*
G01X1538191Y-198164D02*
X1536444Y-198747D01*
X1535134Y-200206D01*
X1534261Y-201955D01*
X1533606Y-204289D01*
X1533388Y-206914D01*
X1533606Y-209539D01*
X1534261Y-211873D01*
X1535134Y-213623D01*
X1536444Y-215081D01*
X1538191Y-215664D01*
X1539937Y-215081D01*
X1541248Y-213623D01*
X1542121Y-211873D01*
X1542776Y-209539D01*
X1542994Y-206914D01*
X1542776Y-204289D01*
X1542121Y-201955D01*
X1541248Y-200206D01*
X1539937Y-198747D01*
X1538191Y-198164D01*
G01X1555691Y-215664D02*
Y-198164D01*
X1553071Y-201664D01*
G01Y-215664D02*
X1558311D01*
G01X1572754D02*
X1573191Y-211873D01*
X1573846Y-208664D01*
X1574719Y-205747D01*
X1575811Y-202539D01*
X1577558Y-198164D01*
X1568824D01*
G01X1463388Y-170664D02*
Y-153164D01*
X1467754D01*
X1469501Y-154039D01*
X1470811Y-155206D01*
X1471903Y-156955D01*
X1472776Y-158998D01*
X1472994Y-161914D01*
X1472776Y-164831D01*
X1471903Y-166873D01*
X1470811Y-168623D01*
X1469501Y-169789D01*
X1467754Y-170664D01*
X1463388D01*
G01X1489621D02*
Y-158998D01*
G01Y-161039D02*
X1488748Y-159873D01*
X1487437Y-159289D01*
X1485909Y-158998D01*
X1484381Y-159581D01*
X1483071Y-160747D01*
X1482197Y-162497D01*
X1481761Y-164831D01*
X1482197Y-167164D01*
X1483071Y-168914D01*
X1484381Y-170081D01*
X1485909Y-170664D01*
X1487437Y-170372D01*
X1488748Y-169498D01*
X1489621Y-168331D01*
G01X1503191Y-153164D02*
Y-170664D01*
G01X1500134Y-158998D02*
X1506248D01*
G01X1517416Y-162789D02*
X1524403D01*
X1523748Y-160747D01*
X1522656Y-159581D01*
X1521128Y-158998D01*
X1519599Y-159289D01*
X1518289Y-160164D01*
X1517416Y-162206D01*
X1516979Y-163956D01*
Y-165706D01*
X1517416Y-167456D01*
X1518508Y-169206D01*
X1519818Y-170372D01*
X1521346Y-170664D01*
X1522874Y-170081D01*
X1524403Y-168331D01*
G54D39*
X121456Y909101D03*
X219283Y471365D03*
X946611Y1087648D03*
X990200Y1131000D03*
X1021900Y1122400D03*
X974700Y1084500D03*
X1762052Y474783D03*
X1836456Y909101D03*
G54D66*
X1002000Y1144000D03*
X1013000D03*
G54D57*
X794631Y1312585D03*
X795101Y1355091D03*
X794880Y1392759D03*
G54D48*
X512799Y1429105D03*
X516674Y1421605D03*
X508924D03*
G54D76*
G01X1099357Y769663D02*
X1100696D01*
G02X1101538Y768821I0J-842D01*
G01Y768121D01*
G02X1100112Y766695I-1426J0D01*
G01X1089179D01*
X1075858Y763864D01*
X1030887Y734659D01*
X969180Y639642D01*
X516413Y345608D01*
X436681Y222833D01*
X271201Y115370D01*
X196266Y99444D01*
X163716Y78302D01*
X162886Y78479D01*
X161628Y77662D01*
X161452Y76832D01*
X160194Y76015D01*
X159364Y76191D01*
X158106Y75374D01*
X157929Y74544D01*
X156671Y73727D01*
X155841Y73903D01*
X154584Y73086D01*
X154407Y72256D01*
X153149Y71439D01*
X152319Y71616D01*
X151061Y70799D01*
X150885Y69969D01*
X147617Y67846D01*
X144501Y63048D01*
X139559Y59838D01*
X138414Y59594D01*
X135551D01*
G02X134983Y60162I0J568D01*
G01Y61269D01*
G01X1104869Y769663D02*
X1103530D01*
G03X1102688Y768821I0J-842D01*
G01Y768121D01*
G02X1100112Y765545I-2576J0D01*
G01X1089300D01*
X1076306Y762783D01*
X1031719Y733827D01*
X970012Y638810D01*
X517245Y344776D01*
X437513Y222001D01*
X271649Y114289D01*
X196714Y98363D01*
X148449Y67014D01*
X145333Y62216D01*
X140007Y58757D01*
X138536Y58444D01*
X135513D01*
G03X134983Y57914I0J-530D01*
G01Y56769D01*
G01X1099357Y854703D02*
X1100696D01*
G02X1101538Y853861I0J-842D01*
G01Y853161D01*
G02X1100112Y851735I-1426J0D01*
G01X1081991D01*
X1052366Y858032D01*
X911448Y828077D01*
X767145Y734403D01*
X766315Y734579D01*
X765057Y733763D01*
X764881Y732933D01*
X763622Y732116D01*
X762792Y732293D01*
X761534Y731476D01*
X761358Y730646D01*
X760100Y729829D01*
X759270Y730006D01*
X758012Y729189D01*
X757835Y728359D01*
X756577Y727542D01*
X755747Y727719D01*
X754489Y726902D01*
X754312Y726072D01*
X606393Y630049D01*
X254384Y555228D01*
X203344Y522071D01*
X139782Y512350D01*
X135551D01*
G02X134983Y512918I0J568D01*
G01Y514025D01*
G01X1104869Y854703D02*
X1103530D01*
G03X1102688Y853861I0J-842D01*
G01Y853161D01*
G02X1100112Y850585I-2576J0D01*
G01X1081870D01*
X1052366Y856856D01*
X911895Y826996D01*
X606840Y628968D01*
X254832Y554147D01*
X203763Y520971D01*
X139870Y511200D01*
X135513D01*
G03X134983Y510670I0J-530D01*
G01Y509525D01*
G01X1095420Y904309D02*
X1096759D01*
G02X1097601Y903467I0J-842D01*
G01Y902767D01*
G02X1096175Y901341I-1426J0D01*
G01X1068600D01*
X1018812Y911912D01*
X761473Y857212D01*
X541231Y888055D01*
X540720Y888733D01*
X539234Y888941D01*
X538557Y888430D01*
X537071Y888638D01*
X536560Y889315D01*
X535075Y889523D01*
X534397Y889012D01*
X532912Y889220D01*
X532401Y889898D01*
X530915Y890106D01*
X530238Y889595D01*
X528752Y889803D01*
X528241Y890480D01*
X526756Y890688D01*
X526079Y890177D01*
X318276Y919277D01*
X138945Y965106D01*
X135551D01*
G02X134983Y965674I0J568D01*
G01Y966781D01*
G01X1100932Y904309D02*
X1099593D01*
G03X1098751Y903467I0J-842D01*
G01Y902767D01*
G02X1096175Y900191I-2576J0D01*
G01X1068479D01*
X1018812Y910736D01*
X761514Y856045D01*
X318053Y918147D01*
X138800Y963956D01*
X135513D01*
G03X134983Y963426I0J-530D01*
G01Y962281D01*
G01X1095420Y762577D02*
X1096759D01*
G02X1097601Y761735I0J-842D01*
G01Y761035D01*
G02X1096175Y759609I-1426J0D01*
G01X1089179D01*
X1076652Y756947D01*
X1037939Y731806D01*
X976076Y636548D01*
X536243Y350907D01*
X522302Y329440D01*
X521472Y329264D01*
X520656Y328006D01*
X520832Y327176D01*
X520015Y325918D01*
X519185Y325742D01*
X518368Y324484D01*
X518544Y323654D01*
X517727Y322396D01*
X516898Y322219D01*
X516081Y320961D01*
X516257Y320131D01*
X515440Y318873D01*
X514610Y318697D01*
X513793Y317439D01*
X513969Y316609D01*
X406086Y150485D01*
X268060Y60886D01*
X261940Y59594D01*
X259763D01*
G02X259195Y60162I0J568D01*
G01Y61269D01*
G01X1100932Y762577D02*
X1099593D01*
G03X1098751Y761735I0J-842D01*
G01Y761035D01*
G02X1096175Y758459I-2576J0D01*
G01X1089300D01*
X1077100Y755866D01*
X1038771Y730974D01*
X976908Y635716D01*
X537075Y350075D01*
X406918Y149653D01*
X268507Y59805D01*
X262061Y58444D01*
X259725D01*
G03X259195Y57914I0J-530D01*
G01Y56769D01*
G01X1095420Y847616D02*
X1096759D01*
G02X1097601Y846774I0J-842D01*
G01Y846074D01*
G02X1096175Y844648I-1426J0D01*
G01X1084956D01*
X1052118Y851629D01*
X929737Y825616D01*
X624932Y627669D01*
X624102Y627846D01*
X622844Y627029D01*
X622668Y626199D01*
X621410Y625382D01*
X620580Y625558D01*
X619322Y624741D01*
X619146Y623911D01*
X617888Y623094D01*
X617058Y623271D01*
X615800Y622454D01*
X615623Y621624D01*
X614365Y620807D01*
X613535Y620983D01*
X612277Y620166D01*
X612101Y619336D01*
X602492Y613096D01*
X327461Y554638D01*
X262344Y512350D01*
X259763D01*
G02X259195Y512918I0J568D01*
G01Y514025D01*
G01X1100932Y847616D02*
X1099593D01*
G03X1098751Y846774I0J-842D01*
G01Y846074D01*
G02X1096175Y843498I-2576J0D01*
G01X1084835D01*
X1052118Y850453D01*
X930185Y824535D01*
X602940Y612015D01*
X327909Y553557D01*
X262686Y511200D01*
X259725D01*
G03X259195Y510670I0J-530D01*
G01Y509525D01*
G01X1099357Y911396D02*
X1100696D01*
G02X1101538Y910554I0J-842D01*
G01Y909854D01*
G02X1100112Y908428I-1426J0D01*
G01X1065845D01*
X1019118Y918357D01*
X811441Y874215D01*
X810729Y874677D01*
X809262Y874365D01*
X808800Y873653D01*
X807333Y873342D01*
X806621Y873804D01*
X805154Y873492D01*
X804692Y872780D01*
X803224Y872468D01*
X802513Y872931D01*
X801046Y872619D01*
X800583Y871907D01*
X799116Y871595D01*
X798405Y872057D01*
X796937Y871745D01*
X796475Y871034D01*
X794025Y870513D01*
X504672Y928763D01*
X266164Y965106D01*
X259763D01*
G02X259195Y965674I0J568D01*
G01Y966781D01*
G01X1104869Y911396D02*
X1103530D01*
G03X1102688Y910554I0J-842D01*
G01Y909854D01*
G02X1100112Y907278I-2576J0D01*
G01X1065724D01*
X1019118Y917181D01*
X794031Y869338D01*
X504472Y927630D01*
X266076Y963956D01*
X259725D01*
G03X259195Y963426I0J-530D01*
G01Y962281D01*
G01X1099357Y755490D02*
X1100696D01*
G02X1101538Y754648I0J-842D01*
G01Y753948D01*
G02X1100112Y752522I-1426J0D01*
G01X1089179D01*
X1077136Y749963D01*
X1042275Y727324D01*
X980224Y631777D01*
X559828Y358748D01*
X402383Y116301D01*
X396790Y89990D01*
X396078Y89527D01*
X395766Y88060D01*
X396228Y87349D01*
X395916Y85881D01*
X395205Y85419D01*
X394893Y83952D01*
X395355Y83240D01*
X395043Y81773D01*
X394331Y81311D01*
X394019Y79844D01*
X394482Y79132D01*
X394170Y77665D01*
X393458Y77203D01*
X393146Y75736D01*
X393608Y75024D01*
X390936Y62453D01*
X390217Y61345D01*
X387949Y59872D01*
X386641Y59594D01*
X383976D01*
G02X383408Y60162I0J568D01*
G01Y61269D01*
G01X1104869Y755490D02*
X1103530D01*
G03X1102688Y754648I0J-842D01*
G01Y753948D01*
G02X1100112Y751372I-2576J0D01*
G01X1089300D01*
X1077584Y748882D01*
X1043107Y726492D01*
X981056Y630945D01*
X560660Y357916D01*
X403464Y115853D01*
X392017Y62006D01*
X391049Y60514D01*
X388397Y58791D01*
X386762Y58444D01*
X383938D01*
G03X383408Y57914I0J-530D01*
G01Y56769D01*
G01X1099357Y840529D02*
X1100696D01*
G02X1101538Y839687I0J-842D01*
G01Y838987D01*
G02X1100112Y837561I-1426J0D01*
G01X1088220D01*
X1064067Y842689D01*
X944076Y817188D01*
X733794Y680628D01*
X732964Y680805D01*
X731706Y679988D01*
X731529Y679158D01*
X730271Y678341D01*
X729441Y678517D01*
X728183Y677700D01*
X728007Y676870D01*
X726749Y676054D01*
X725919Y676230D01*
X724661Y675413D01*
X724485Y674583D01*
X723227Y673766D01*
X722397Y673942D01*
X721139Y673126D01*
X720962Y672296D01*
X517434Y540121D01*
X386630Y512350D01*
X383976D01*
G02X383408Y512918I0J568D01*
G01Y514025D01*
G01X1104869Y840529D02*
X1103530D01*
G03X1102688Y839687I0J-842D01*
G01Y838987D01*
G02X1100112Y836411I-2576J0D01*
G01X1088099D01*
X1064067Y841513D01*
X944524Y816107D01*
X517881Y539040D01*
X386751Y511200D01*
X383938D01*
G03X383408Y510670I0J-530D01*
G01Y509525D01*
G01X1095420Y918482D02*
X1096759D01*
G02X1097601Y917640I0J-842D01*
G01Y916940D01*
G02X1096175Y915514I-1426J0D01*
G01X1062943D01*
X1018419Y924976D01*
X816500Y882058D01*
X537719Y938964D01*
X537251Y939671D01*
X535781Y939971D01*
X535073Y939504D01*
X533604Y939804D01*
X533136Y940511D01*
X531666Y940811D01*
X530958Y940344D01*
X529489Y940644D01*
X529021Y941351D01*
X527551Y941651D01*
X526843Y941184D01*
X525373Y941484D01*
X524906Y942191D01*
X523436Y942491D01*
X522728Y942024D01*
X480972Y950547D01*
X386628Y965106D01*
X383976D01*
G02X383408Y965674I0J568D01*
G01Y966781D01*
G01X1100932Y918482D02*
X1099593D01*
G03X1098751Y917640I0J-842D01*
G01Y916940D01*
G02X1096175Y914364I-2576J0D01*
G01X1062822D01*
X1018419Y923800D01*
X816505Y880883D01*
X480769Y949414D01*
X386539Y963956D01*
X383938D01*
G03X383408Y963426I0J-530D01*
G01Y962281D01*
G01X1095420Y748403D02*
X1096759D01*
G02X1097601Y747561I0J-842D01*
G01Y746861D01*
G02X1096175Y745435I-1426J0D01*
G01X1089179D01*
X1079257Y743326D01*
X1049520Y724015D01*
X988044Y629352D01*
X652703Y411563D01*
X580560Y300467D01*
X579730Y300291D01*
X578913Y299033D01*
X579089Y298203D01*
X578272Y296945D01*
X577442Y296769D01*
X576625Y295511D01*
X576802Y294681D01*
X575985Y293423D01*
X575155Y293246D01*
X574338Y291988D01*
X574514Y291158D01*
X573697Y289900D01*
X572867Y289724D01*
X572050Y288466D01*
X572227Y287636D01*
X561920Y271764D01*
X518992Y69791D01*
X513248Y60950D01*
X511409Y59757D01*
X510642Y59594D01*
X508188D01*
G02X507620Y60162I0J568D01*
G01Y61269D01*
G01X1100932Y748403D02*
X1099593D01*
G03X1098751Y747561I0J-842D01*
G01Y746861D01*
G02X1096175Y744285I-2576J0D01*
G01X1089300D01*
X1079705Y742245D01*
X1050352Y723183D01*
X988876Y628520D01*
X653535Y410731D01*
X563001Y271316D01*
X520073Y69343D01*
X514079Y60118D01*
X511857Y58676D01*
X510763Y58444D01*
X508150D01*
G03X507620Y57914I0J-530D01*
G01Y56769D01*
G01X1095420Y833443D02*
X1096759D01*
G02X1097601Y832601I0J-842D01*
G01Y831901D01*
G02X1096175Y830475I-1426J0D01*
G01X1091966D01*
X1071791Y834763D01*
X947488Y808347D01*
X708212Y652961D01*
X707327Y653150D01*
X706069Y652333D01*
X705881Y651447D01*
X704623Y650630D01*
X703737Y650819D01*
X702479Y650002D01*
X702291Y649116D01*
X633909Y604709D01*
X633079Y604885D01*
X631821Y604068D01*
X631645Y603238D01*
X630387Y602421D01*
X629557Y602597D01*
X628299Y601780D01*
X628122Y600950D01*
X564154Y559409D01*
X511044Y512350D01*
X508188D01*
G02X507620Y512918I0J568D01*
G01Y514025D01*
G01X1100932Y833443D02*
X1099593D01*
G03X1098751Y832601I0J-842D01*
G01Y831901D01*
G02X1096175Y829325I-2576J0D01*
G01X1091845D01*
X1071791Y833587D01*
X947936Y807266D01*
X564853Y558491D01*
X511481Y511200D01*
X508150D01*
G03X507620Y510670I0J-530D01*
G01Y509525D01*
G01X1099357Y925569D02*
X1100696D01*
G02X1101538Y924727I0J-842D01*
G01Y924027D01*
G02X1100112Y922601I-1426J0D01*
G01X1058702D01*
X1018382Y931170D01*
X872731Y900213D01*
X866408Y899047D01*
X621322Y948710D01*
X539611Y960900D01*
X539107Y961582D01*
X537623Y961803D01*
X536941Y961298D01*
X535457Y961519D01*
X534953Y962201D01*
X533469Y962423D01*
X532787Y961918D01*
X531303Y962139D01*
X530798Y962821D01*
X529315Y963042D01*
X528633Y962537D01*
X527149Y962759D01*
X526644Y963441D01*
X525161Y963662D01*
X524479Y963157D01*
X511509Y965092D01*
X511493Y965094D01*
X511411Y965106D01*
X508188D01*
G02X507620Y965674I0J568D01*
G01Y966781D01*
G01X1104869Y925569D02*
X1103530D01*
G03X1102688Y924727I0J-842D01*
G01Y924027D01*
G02X1100112Y921451I-2576J0D01*
G01X1058581D01*
X1018382Y929994D01*
X872955Y899084D01*
X866398Y897875D01*
X621123Y947576D01*
X511339Y963953D01*
X511330Y963954D01*
X511325Y963955D01*
Y963956D01*
X508150D01*
G03X507620Y963426I0J-530D01*
G01Y962281D01*
G01X1099357Y741317D02*
X1100696D01*
G02X1101538Y740475I0J-842D01*
G01Y739775D01*
G02X1100112Y738349I-1426J0D01*
G01X1089179D01*
X1081750Y736771D01*
X1053500Y718426D01*
X993098Y625419D01*
X762950Y475934D01*
X709586Y393750D01*
X644390Y87022D01*
X643678Y86560D01*
X643366Y85093D01*
X643828Y84381D01*
X643517Y82914D01*
X642805Y82452D01*
X642493Y80985D01*
X642955Y80273D01*
X642643Y78806D01*
X641932Y78344D01*
X641620Y76876D01*
X642082Y76165D01*
X641770Y74697D01*
X641058Y74235D01*
X640747Y72768D01*
X641209Y72056D01*
X639617Y64568D01*
X637284Y60975D01*
X635263Y59663D01*
X634939Y59594D01*
X632401D01*
G02X631833Y60162I0J568D01*
G01Y61269D01*
G01X1104869Y741317D02*
X1103530D01*
G03X1102688Y740475I0J-842D01*
G01Y739775D01*
G02X1100112Y737199I-2576J0D01*
G01X1089300D01*
X1082198Y735690D01*
X1054332Y717594D01*
X993930Y624587D01*
X763782Y475102D01*
X710667Y393302D01*
X640698Y64120D01*
X638116Y60143D01*
X635711Y58582D01*
X635061Y58444D01*
X632363D01*
G03X631833Y57914I0J-530D01*
G01Y56769D01*
G01X1099357Y826356D02*
X1100696D01*
G02X1101538Y825514I0J-842D01*
G01Y824814D01*
G02X1100112Y823388I-1426J0D01*
G01X1065063D01*
X953484Y799672D01*
X723669Y650428D01*
X666262Y562028D01*
X666261D01*
X665431Y561851D01*
X664614Y560593D01*
X664791Y559763D01*
X663974Y558505D01*
X663144Y558329D01*
X662327Y557071D01*
X662503Y556241D01*
X661686Y554983D01*
X660856Y554806D01*
X660039Y553548D01*
X660216Y552718D01*
X659399Y551460D01*
X658569Y551284D01*
X657752Y550026D01*
X657928Y549196D01*
X634269Y512764D01*
X633632Y512350D01*
X632401D01*
G02X631833Y512918I0J568D01*
G01Y514025D01*
G01X1104869Y826356D02*
X1103530D01*
G03X1102688Y825514I0J-842D01*
G01Y824814D01*
G02X1100112Y822238I-2576J0D01*
G01X1065184D01*
X953932Y798591D01*
X724501Y649596D01*
X635101Y511932D01*
X633973Y511200D01*
X632363D01*
G03X631833Y510670I0J-530D01*
G01Y509525D01*
G01X1095420Y932655D02*
X1096759D01*
G02X1097601Y931813I0J-842D01*
G01Y931113D01*
G02X1096175Y929687I-1426J0D01*
G01X1054978D01*
X1018529Y937434D01*
X907759Y913889D01*
X864620Y923058D01*
X864158Y923769D01*
X862691Y924081D01*
X861979Y923619D01*
X860512Y923931D01*
X860050Y924642D01*
X858583Y924954D01*
X857871Y924492D01*
X856404Y924804D01*
X855942Y925516D01*
X854474Y925827D01*
X853763Y925365D01*
X852296Y925677D01*
X851833Y926389D01*
X850366Y926701D01*
X849655Y926238D01*
X719519Y953897D01*
X637609Y965106D01*
X632401D01*
G02X631833Y965674I0J568D01*
G01Y966781D01*
G01X1100932Y932655D02*
X1099593D01*
G03X1098751Y931813I0J-842D01*
G01Y931113D01*
G02X1096175Y928537I-2576J0D01*
G01X1054857D01*
X1018529Y936258D01*
X907759Y912713D01*
X719321Y952763D01*
X637530Y963956D01*
X632363D01*
G03X631833Y963426I0J-530D01*
G01Y962281D01*
G01X1095420Y734230D02*
X1096759D01*
G02X1097601Y733388I0J-842D01*
G01Y732688D01*
G02X1096175Y731262I-1426J0D01*
G01X1088379D01*
X1084846Y730511D01*
X1057219Y712571D01*
X997982Y621354D01*
X795435Y489816D01*
X781284Y468023D01*
X771403Y421536D01*
X783389Y365142D01*
X754278Y228186D01*
X753567Y227723D01*
X753255Y226256D01*
X753717Y225545D01*
X753405Y224077D01*
X752694Y223615D01*
X752382Y222148D01*
X752844Y221436D01*
X752532Y219969D01*
X751820Y219507D01*
X751509Y218040D01*
X751971Y217328D01*
X751659Y215861D01*
X750947Y215399D01*
X750635Y213932D01*
X751097Y213220D01*
X740467Y163204D01*
X750787Y114653D01*
X761005Y66581D01*
X759789Y60864D01*
X759295Y60105D01*
X758511Y59594D01*
X756614D01*
G02X756046Y60162I0J568D01*
G01Y61269D01*
G01X1100932Y734230D02*
X1099593D01*
G03X1098751Y733388I0J-842D01*
G01Y732688D01*
G02X1096175Y730112I-2576J0D01*
G01X1088500D01*
X1085294Y729430D01*
X1058051Y711739D01*
X998814Y620522D01*
X796267Y488984D01*
X782365Y467575D01*
X772579Y421536D01*
X784565Y365142D01*
X741643Y163204D01*
X762181Y66581D01*
X760870Y60416D01*
X760127Y59273D01*
X758853Y58444D01*
X756576D01*
G03X756046Y57914I0J-530D01*
G01Y56769D01*
G01X1095420Y819270D02*
X1096759D01*
G02X1097601Y818428I0J-842D01*
G01Y817728D01*
G02X1096175Y816302I-1426J0D01*
G01X1082843D01*
X1031407Y805370D01*
X900998Y720681D01*
X828494Y648177D01*
X825054Y642880D01*
X824169Y642692D01*
X823352Y641434D01*
X823540Y640549D01*
X822723Y639291D01*
X821838Y639102D01*
X821021Y637844D01*
X821209Y636959D01*
X820392Y635701D01*
X819562Y635524D01*
X818745Y634266D01*
X818921Y633436D01*
X818104Y632178D01*
X817274Y632002D01*
X816457Y630744D01*
X816634Y629914D01*
X771751Y560800D01*
X762094Y515149D01*
X760789Y513139D01*
X759786Y512487D01*
X759141Y512350D01*
X756614D01*
G02X756046Y512918I0J568D01*
G01Y514025D01*
G01X1100932Y819270D02*
X1099593D01*
G03X1098751Y818428I0J-842D01*
G01Y817728D01*
G02X1096175Y815152I-2576J0D01*
G01X1082964D01*
X1031855Y804289D01*
X901726Y719782D01*
X829393Y647449D01*
X772832Y560353D01*
X763175Y514702D01*
X761621Y512308D01*
X760234Y511406D01*
X759263Y511200D01*
X756576D01*
G03X756046Y510670I0J-530D01*
G01Y509525D01*
G01X1099357Y939742D02*
X1100696D01*
G02X1101538Y938900I0J-842D01*
G01Y938200D01*
G02X1100112Y936774I-1426J0D01*
G01X1051469D01*
X1035291Y940213D01*
Y940214D01*
X1018756Y943728D01*
X959961Y931230D01*
X880511Y941727D01*
X879995Y942400D01*
X878508Y942597D01*
X877834Y942081D01*
X876347Y942277D01*
X875831Y942951D01*
X874344Y943147D01*
X873671Y942631D01*
X872184Y942827D01*
X871667Y943501D01*
X870180Y943697D01*
X869507Y943181D01*
X868020Y943378D01*
X867504Y944051D01*
X866016Y944247D01*
X865343Y943731D01*
X843851Y946571D01*
X759822Y965106D01*
X756614D01*
G02X756046Y965674I0J568D01*
G01Y966781D01*
G01X1104869Y939742D02*
X1103530D01*
G03X1102688Y938900I0J-842D01*
G01Y938200D01*
G02X1100112Y935624I-2576J0D01*
G01X1051348D01*
X1018756Y942552D01*
X960007Y930063D01*
X901756Y937759D01*
X843651Y945437D01*
X759696Y963956D01*
X756576D01*
G03X756046Y963426I0J-530D01*
G01Y962281D01*
G01X1095420Y691711D02*
X1096857D01*
G02X1097601Y690967I0J-744D01*
G01Y689867D01*
G03X1099875Y687593I2274J0D01*
G01X1133936D01*
X1142610Y685750D01*
X1146804Y683025D01*
X1182029Y628784D01*
X1231098Y397742D01*
X1258425Y61520D01*
Y54325D01*
G02X1257750Y53650I-675J0D01*
G01X1256750D01*
G01X1100932Y691711D02*
X1099495D01*
G03X1098751Y690967I0J-744D01*
G01Y689867D01*
G03X1099875Y688743I1124J0D01*
G01X1134057D01*
X1143058Y686831D01*
X1147636Y683857D01*
X1183110Y629231D01*
X1206333Y519891D01*
X1207045Y519429D01*
X1207356Y517961D01*
X1206894Y517250D01*
X1207206Y515783D01*
X1207917Y515320D01*
X1208229Y513853D01*
X1207767Y513142D01*
X1208078Y511674D01*
X1208790Y511212D01*
X1209101Y509745D01*
X1208639Y509033D01*
X1208951Y507566D01*
X1209662Y507104D01*
X1209974Y505636D01*
X1209512Y504925D01*
X1232239Y397909D01*
X1259575Y61567D01*
Y54325D01*
G03X1260250Y53650I675J0D01*
G01X1261250D01*
G01X1099357Y698797D02*
X1100794D01*
G02X1101538Y698053I0J-744D01*
G01Y696953D01*
G03X1103812Y694679I2274J0D01*
G01X1135508D01*
X1145112Y692638D01*
X1153688Y687078D01*
X1189532Y631882D01*
X1221776Y480185D01*
X1327537Y317332D01*
X1357778Y222541D01*
X1382638Y60564D01*
Y54338D01*
G02X1381950Y53650I-688J0D01*
G01X1380963D01*
G01X1104869Y698797D02*
X1103432D01*
G03X1102688Y698053I0J-744D01*
G01Y696953D01*
G03X1103812Y695829I1124J0D01*
G01X1135629D01*
X1145559Y693719D01*
X1154519Y687910D01*
X1190613Y632330D01*
X1222857Y480633D01*
X1313841Y340533D01*
X1314726Y340345D01*
X1315543Y339087D01*
X1315355Y338202D01*
X1316172Y336944D01*
X1317058Y336755D01*
X1317874Y335497D01*
X1317686Y334612D01*
X1318503Y333354D01*
X1319389Y333166D01*
X1320206Y331908D01*
X1320017Y331023D01*
X1320834Y329765D01*
X1321720Y329577D01*
X1322537Y328319D01*
X1322349Y327433D01*
X1328586Y317829D01*
X1358901Y222805D01*
X1383788Y60652D01*
Y54338D01*
G03X1384476Y53650I688J0D01*
G01X1385463D01*
G01X1095420Y705884D02*
X1096857D01*
G02X1097601Y705140I0J-744D01*
G01Y704040D01*
G03X1099875Y701766I2274J0D01*
G01X1136561D01*
X1148775Y699152D01*
X1159102Y692446D01*
X1197012Y634071D01*
X1227711Y489645D01*
X1506850Y59807D01*
Y54250D01*
G02X1506250Y53650I-600J0D01*
G01X1505175D01*
G01X1100932Y705884D02*
X1099495D01*
G03X1098751Y705140I0J-744D01*
G01Y704040D01*
G03X1099875Y702916I1124J0D01*
G01X1136683D01*
X1149224Y700233D01*
X1159934Y693278D01*
X1198093Y634519D01*
X1228792Y490093D01*
X1488302Y90481D01*
X1489187Y90292D01*
X1490004Y89034D01*
X1489816Y88149D01*
X1490633Y86891D01*
X1491518Y86703D01*
X1492335Y85445D01*
X1492147Y84560D01*
X1492964Y83302D01*
X1493849Y83113D01*
X1494666Y81855D01*
X1494478Y80970D01*
X1495295Y79712D01*
X1496180Y79524D01*
X1496997Y78266D01*
X1496809Y77381D01*
X1508000Y60148D01*
Y54250D01*
G03X1508600Y53650I600J0D01*
G01X1509675D01*
G01X1099357Y712970D02*
X1100794D01*
G02X1101538Y712226I0J-744D01*
G01Y711126D01*
G03X1103812Y708852I2274J0D01*
G01X1136200D01*
X1150615Y705788D01*
X1169099Y693785D01*
X1204861Y638718D01*
X1235465Y494733D01*
X1351217Y316491D01*
X1552732Y185630D01*
X1599469Y147659D01*
X1609895Y130419D01*
X1631063Y58120D01*
Y54263D01*
G02X1630450Y53650I-613J0D01*
G01X1629388D01*
G01X1104869Y712970D02*
X1103432D01*
G03X1102688Y712226I0J-744D01*
G01Y711126D01*
G03X1103812Y710002I1124J0D01*
G01X1136321D01*
X1151063Y706869D01*
X1169931Y694617D01*
X1205942Y639166D01*
X1236546Y495181D01*
X1352049Y317323D01*
X1473465Y238477D01*
X1474350Y238666D01*
X1475609Y237849D01*
X1475797Y236963D01*
X1477055Y236146D01*
X1477940Y236335D01*
X1479198Y235518D01*
X1479386Y234632D01*
X1480644Y233815D01*
X1481530Y234004D01*
X1482788Y233187D01*
X1482976Y232301D01*
X1484234Y231484D01*
X1485119Y231673D01*
X1486377Y230856D01*
X1486565Y229970D01*
X1553410Y186561D01*
X1600350Y148426D01*
X1610957Y130886D01*
X1632213Y58285D01*
Y54263D01*
G03X1632826Y53650I613J0D01*
G01X1633888D01*
G01X1095420Y720057D02*
X1096857D01*
G02X1097601Y719313I0J-744D01*
G01Y718213D01*
G03X1099875Y715939I2274J0D01*
G01X1135622D01*
X1150159Y713360D01*
X1181928Y692725D01*
X1210525Y648690D01*
X1242415Y498667D01*
X1357669Y321192D01*
X1555116Y192972D01*
X1555117D01*
X1555118Y192971D01*
X1752568Y64749D01*
X1755073Y58850D01*
X1755275Y57900D01*
Y54275D01*
G02X1754650Y53650I-625J0D01*
G01X1753600D01*
G01X1100932Y720057D02*
X1099495D01*
G03X1098751Y719313I0J-744D01*
G01Y718213D01*
G03X1099875Y717089I1124J0D01*
G01X1135724D01*
X1150590Y714452D01*
X1182760Y693557D01*
X1211606Y649138D01*
X1243496Y499115D01*
X1358501Y322024D01*
X1429704Y275786D01*
X1430589Y275974D01*
X1431847Y275158D01*
X1432035Y274272D01*
X1433293Y273455D01*
X1434178Y273643D01*
X1435436Y272827D01*
X1435625Y271941D01*
X1436883Y271124D01*
X1437768Y271312D01*
X1439026Y270496D01*
X1439214Y269610D01*
X1440472Y268793D01*
X1441358Y268981D01*
X1442616Y268165D01*
X1442804Y267279D01*
X1753490Y65523D01*
X1756175Y59198D01*
X1756425Y58021D01*
Y54275D01*
G03X1757050Y53650I625J0D01*
G01X1758100D01*
G01X1099357Y727144D02*
X1100794D01*
G02X1101538Y726400I0J-744D01*
G01Y725300D01*
G03X1103812Y723026I2274J0D01*
G01X1135767D01*
X1159949Y717885D01*
X1188423Y699393D01*
X1218199Y653542D01*
X1249997Y503978D01*
X1364846Y327126D01*
X1668347Y130030D01*
X1839763Y93592D01*
X1875957Y66358D01*
X1879488Y61524D01*
Y54288D01*
G02X1878850Y53650I-638J0D01*
G01X1877813D01*
G01X1104869Y727144D02*
X1103432D01*
G03X1102688Y726400I0J-744D01*
G01Y725300D01*
G03X1103812Y724176I1124J0D01*
G01X1135888D01*
X1160397Y718966D01*
X1189255Y700225D01*
X1219280Y653990D01*
X1251078Y504426D01*
X1365678Y327958D01*
X1548941Y208945D01*
X1549771Y209122D01*
X1551029Y208305D01*
X1551205Y207475D01*
X1552463Y206658D01*
X1553293Y206834D01*
X1554551Y206017D01*
X1554728Y205187D01*
X1555986Y204370D01*
X1556816Y204547D01*
X1558074Y203730D01*
X1558250Y202900D01*
X1559508Y202083D01*
X1560338Y202259D01*
X1561596Y201442D01*
X1561773Y200612D01*
X1668795Y131111D01*
X1840251Y94664D01*
X1876786Y67175D01*
X1880638Y61900D01*
Y54262D01*
G03X1881250Y53650I612J0D01*
G01X1882313D01*
G01X1095420Y776750D02*
X1097018D01*
G02X1097601Y776167I0J-583D01*
G01Y774667D01*
G03X1099636Y772632I2035J0D01*
G01X1141853D01*
X1207944Y758586D01*
X1217628Y752296D01*
X1234445Y726395D01*
X1268828Y564712D01*
Y564711D01*
X1258425Y515219D01*
Y507025D01*
G02X1257806Y506406I-619J0D01*
G01X1256750D01*
G01X1100932Y776750D02*
X1099334D01*
G03X1098751Y776167I0J-583D01*
G01Y774667D01*
G03X1099636Y773782I885J0D01*
G01X1141974D01*
X1208392Y759667D01*
X1218460Y753128D01*
X1235526Y726843D01*
X1262345Y600729D01*
X1263057Y600267D01*
X1263369Y598800D01*
X1262907Y598088D01*
X1263219Y596621D01*
X1263930Y596159D01*
X1264242Y594692D01*
X1263780Y593980D01*
X1264092Y592513D01*
X1264804Y592051D01*
X1265116Y590584D01*
X1264654Y589872D01*
X1264966Y588405D01*
X1265678Y587943D01*
X1265990Y586476D01*
X1265528Y585764D01*
X1270004Y564713D01*
X1259575Y515098D01*
Y507025D01*
G03X1260194Y506406I619J0D01*
G01X1261250D01*
G01X1099357Y783836D02*
X1100955D01*
G02X1101538Y783253I0J-583D01*
G01Y781753D01*
G03X1103573Y779718I2035J0D01*
G01X1147144D01*
X1207474Y766896D01*
X1224644Y755745D01*
X1382638Y512464D01*
Y507038D01*
G02X1382006Y506406I-632J0D01*
G01X1380963D01*
G01X1104869Y783836D02*
X1103271D01*
G03X1102688Y783253I0J-583D01*
G01Y781753D01*
G03X1103573Y780868I885J0D01*
G01X1147265D01*
X1207922Y767977D01*
X1225476Y756577D01*
X1266027Y694136D01*
X1266857Y693960D01*
X1267674Y692702D01*
X1267498Y691872D01*
X1268314Y690614D01*
X1269144Y690438D01*
X1269961Y689180D01*
X1269785Y688350D01*
X1270602Y687092D01*
X1271432Y686915D01*
X1272249Y685657D01*
X1272073Y684827D01*
X1272890Y683569D01*
X1273720Y683393D01*
X1274537Y682135D01*
X1274360Y681305D01*
X1383788Y512805D01*
Y507038D01*
G03X1384420Y506406I632J0D01*
G01X1385463D01*
G01X1095420Y790923D02*
X1097018D01*
G02X1097601Y790340I0J-583D01*
G01Y788840D01*
G03X1099636Y786805I2035J0D01*
G01X1168661D01*
X1316497Y755381D01*
X1400145Y701059D01*
X1504844Y539837D01*
X1506850Y530400D01*
Y507050D01*
G02X1506206Y506406I-644J0D01*
G01X1505175D01*
G01X1100932Y790923D02*
X1099334D01*
G03X1098751Y790340I0J-583D01*
G01Y788840D01*
G03X1099636Y787955I885J0D01*
G01X1168782D01*
X1316945Y756462D01*
X1400977Y701891D01*
X1485788Y571293D01*
X1486618Y571117D01*
X1487435Y569859D01*
X1487258Y569029D01*
X1488075Y567771D01*
X1488905Y567594D01*
X1489722Y566336D01*
X1489546Y565506D01*
X1490363Y564248D01*
X1491193Y564072D01*
X1492010Y562814D01*
X1491833Y561984D01*
X1492650Y560726D01*
X1493480Y560550D01*
X1494297Y559292D01*
X1494121Y558462D01*
X1505925Y540285D01*
X1508000Y530521D01*
Y507050D01*
G03X1508644Y506406I644J0D01*
G01X1509675D01*
G01X1099357Y798010D02*
X1100955D01*
G02X1101538Y797427I0J-583D01*
G01Y795927D01*
G03X1103573Y793892I2035J0D01*
G01X1193373D01*
X1317420Y767524D01*
X1591247Y589778D01*
X1629751Y530489D01*
X1631063Y524317D01*
Y506963D01*
G02X1630506Y506406I-557J0D01*
G01X1629388D01*
G01X1104869Y798010D02*
X1103271D01*
G03X1102688Y797427I0J-583D01*
G01Y795927D01*
G03X1103573Y795042I885J0D01*
G01X1193494D01*
X1317867Y768605D01*
X1592079Y590610D01*
X1598855Y580176D01*
X1599685Y579999D01*
X1600502Y578741D01*
X1600326Y577911D01*
X1601143Y576653D01*
X1601973Y576477D01*
X1602790Y575219D01*
X1602613Y574389D01*
X1603430Y573131D01*
X1604260Y572955D01*
X1605077Y571697D01*
X1604901Y570867D01*
X1605718Y569609D01*
X1606548Y569432D01*
X1607365Y568174D01*
X1607188Y567344D01*
X1630832Y530937D01*
X1632213Y524438D01*
Y506963D01*
G03X1632770Y506406I557J0D01*
G01X1633888D01*
G01X1095420Y805096D02*
X1097018D01*
G02X1097601Y804513I0J-583D01*
G01Y803013D01*
G03X1099636Y800978I2035J0D01*
G01X1189240D01*
X1344172Y768130D01*
X1721445Y523128D01*
X1753311Y516354D01*
X1754293Y514842D01*
X1755275Y513328D01*
Y507075D01*
G02X1754606Y506406I-669J0D01*
G01X1753600D01*
G01X1100932Y805096D02*
X1099334D01*
G03X1098751Y804513I0J-583D01*
G01Y803013D01*
G03X1099636Y802128I885J0D01*
G01X1189361D01*
X1344619Y769211D01*
X1607083Y598767D01*
X1607913Y598944D01*
X1609171Y598127D01*
X1609347Y597297D01*
X1610605Y596480D01*
X1611435Y596656D01*
X1612693Y595839D01*
X1612870Y595009D01*
X1614128Y594193D01*
X1614958Y594369D01*
X1616216Y593552D01*
X1616392Y592722D01*
X1617650Y591905D01*
X1618480Y592081D01*
X1619738Y591265D01*
X1619915Y590435D01*
X1721893Y524209D01*
X1754017Y517381D01*
X1756425Y513669D01*
Y507075D01*
G03X1757094Y506406I669J0D01*
G01X1758100D01*
G01X1099357Y812183D02*
X1100955D01*
G02X1101538Y811600I0J-583D01*
G01Y810100D01*
G03X1103573Y808065I2035J0D01*
G01X1186348D01*
X1350071Y773269D01*
X1683749Y556577D01*
X1872705Y516413D01*
X1877957Y513003D01*
X1879488Y510648D01*
Y506988D01*
G02X1878906Y506406I-582J0D01*
G01X1877813D01*
G01X1104869Y812183D02*
X1103271D01*
G03X1102688Y811600I0J-583D01*
G01Y810100D01*
G03X1103573Y809215I885J0D01*
G01X1186469D01*
X1350519Y774350D01*
X1438919Y716943D01*
X1439749Y717119D01*
X1441007Y716302D01*
X1441183Y715472D01*
X1442441Y714655D01*
X1443271Y714832D01*
X1444529Y714015D01*
X1444705Y713185D01*
X1445963Y712368D01*
X1446793Y712544D01*
X1448051Y711727D01*
X1448228Y710897D01*
X1449486Y710080D01*
X1450316Y710257D01*
X1451574Y709440D01*
X1451750Y708610D01*
X1684197Y557658D01*
X1873153Y517494D01*
X1878788Y513835D01*
X1880638Y510989D01*
Y506988D01*
G03X1881220Y506406I582J0D01*
G01X1882313D01*
G01X1099357Y868876D02*
X1100814D01*
G03X1101538Y869600I0J724D01*
G01Y870600D01*
G02X1103883Y872945I2345J0D01*
G01X1143956D01*
X1331392Y893070D01*
X1695688Y944695D01*
X1751471Y964693D01*
X1753803D01*
G03X1754340Y965230I0J537D01*
G01Y966361D01*
G01X1104869Y868876D02*
X1103412D01*
G02X1102688Y869600I0J724D01*
G01Y870600D01*
G02X1103883Y871795I1195J0D01*
G01X1144018D01*
X1331514Y891926D01*
X1331554Y891931D01*
X1590897Y928683D01*
X1591575Y928173D01*
X1593060Y928383D01*
X1593570Y929062D01*
X1595055Y929272D01*
X1595734Y928762D01*
X1597219Y928973D01*
X1597729Y929651D01*
X1599214Y929861D01*
X1599892Y929352D01*
X1601377Y929562D01*
X1601887Y930240D01*
X1603372Y930451D01*
X1604051Y929941D01*
X1605536Y930151D01*
X1606046Y930830D01*
X1695968Y943573D01*
X1751671Y963543D01*
X1753827D01*
G02X1754340Y963030I0J-513D01*
G01Y961861D01*
G01X1095420Y861789D02*
X1096790D01*
G03X1097601Y862600I0J811D01*
G01Y863500D01*
G02X1099959Y865858I2358J0D01*
G01X1141737D01*
X1342266Y884556D01*
X1768774Y936846D01*
X1857963Y964686D01*
X1877896D01*
G03X1878553Y965343I0J657D01*
G01Y966361D01*
G01X1100932Y861789D02*
X1099562D01*
G02X1098751Y862600I0J811D01*
G01Y863500D01*
G02X1099959Y864708I1208J0D01*
G01X1141791D01*
X1342389Y883412D01*
X1711916Y928715D01*
X1712584Y928193D01*
X1714073Y928375D01*
X1714595Y929044D01*
X1716084Y929227D01*
X1716753Y928704D01*
X1718242Y928887D01*
X1718764Y929555D01*
X1720253Y929738D01*
X1720922Y929215D01*
X1722411Y929398D01*
X1722933Y930066D01*
X1724422Y930249D01*
X1725090Y929726D01*
X1726579Y929909D01*
X1727102Y930577D01*
X1769021Y935717D01*
X1858139Y963536D01*
X1877896D01*
G02X1878553Y962879I0J-657D01*
G01Y961861D01*
G01X1099357Y897222D02*
X1100760D01*
G03X1101538Y898000I0J778D01*
G01Y898900D01*
G02X1103929Y901291I2391J0D01*
G01X1142390D01*
X1251351Y964686D01*
X1256790D01*
G03X1257490Y965386I0J700D01*
G01Y966361D01*
G01X1104869Y897222D02*
X1103466D01*
G02X1102688Y898000I0J778D01*
G01Y898900D01*
G02X1103929Y900141I1241J0D01*
G01X1142701D01*
X1206817Y937444D01*
X1207636Y937227D01*
X1208932Y937982D01*
X1209149Y938802D01*
X1210446Y939556D01*
X1211266Y939340D01*
X1212563Y940094D01*
X1212780Y940914D01*
X1214076Y941669D01*
X1214897Y941452D01*
X1216193Y942206D01*
X1216410Y943026D01*
X1217706Y943781D01*
X1218527Y943564D01*
X1219823Y944318D01*
X1220040Y945138D01*
X1251662Y963536D01*
X1256790D01*
G02X1257490Y962836I0J-700D01*
G01Y961861D01*
G01X1095420Y890136D02*
X1096637D01*
G03X1097601Y891100I0J964D01*
G01Y891800D01*
G02X1100006Y894205I2405J0D01*
G01X1144938D01*
X1190368Y906103D01*
X1296973Y934022D01*
X1378781Y964706D01*
X1381056D01*
G03X1381663Y965313I0J607D01*
G01Y966381D01*
G01X1100932Y890136D02*
X1099715D01*
G02X1098751Y891100I0J964D01*
G01Y891800D01*
G02X1100006Y893055I1255J0D01*
G01X1145088D01*
X1190659Y904989D01*
X1227364Y914602D01*
X1228096Y914173D01*
X1229547Y914553D01*
X1229975Y915286D01*
X1231427Y915666D01*
X1232159Y915237D01*
X1233610Y915618D01*
X1234038Y916350D01*
X1235489Y916730D01*
X1236222Y916302D01*
X1237673Y916682D01*
X1238101Y917414D01*
X1239552Y917794D01*
X1240285Y917366D01*
X1241736Y917746D01*
X1242164Y918478D01*
X1297328Y932926D01*
X1378990Y963556D01*
X1381056D01*
G02X1381663Y962949I0J-607D01*
G01Y961881D01*
G01X1099357Y883049D02*
X1100687D01*
G03X1101538Y883900I0J851D01*
G01Y885000D01*
G02X1103656Y887118I2118J0D01*
G01X1145176D01*
X1223866Y900069D01*
X1302555Y913018D01*
X1401310Y935617D01*
X1499923Y964646D01*
X1505056D01*
G03X1505875Y965465I0J819D01*
G01Y966321D01*
G01X1104869Y883049D02*
X1103539D01*
G02X1102688Y883900I0J851D01*
G01Y885000D01*
G02X1103656Y885968I968J0D01*
G01X1145271D01*
X1302783Y911890D01*
X1401601Y934503D01*
X1419708Y939833D01*
X1420453Y939427D01*
X1421892Y939851D01*
X1422298Y940596D01*
X1423737Y941020D01*
X1424482Y940613D01*
X1425921Y941037D01*
X1426327Y941782D01*
X1427766Y942206D01*
X1428511Y941800D01*
X1429950Y942223D01*
X1430356Y942968D01*
X1431795Y943392D01*
X1432540Y942985D01*
X1433979Y943409D01*
X1434385Y944154D01*
X1500089Y963496D01*
X1505056D01*
G02X1505875Y962677I0J-819D01*
G01Y961821D01*
G01X1095420Y875962D02*
X1096963D01*
G03X1097601Y876600I0J638D01*
G01Y877800D01*
G02X1099832Y880031I2231J0D01*
G01X1147009D01*
X1326814Y902675D01*
X1426477Y918548D01*
X1468384Y925223D01*
X1526142Y934422D01*
X1625026Y965206D01*
X1629556D01*
G03X1630088Y965738I0J532D01*
G01Y966881D01*
G01X1100932Y875962D02*
X1099389D01*
G02X1098751Y876600I0J638D01*
G01Y877800D01*
G02X1099832Y878881I1081J0D01*
G01X1147082D01*
X1326976Y901536D01*
X1526405Y933299D01*
X1604476Y957603D01*
X1605227Y957209D01*
X1606659Y957655D01*
X1607054Y958406D01*
X1608486Y958852D01*
X1609237Y958457D01*
X1610669Y958903D01*
X1611064Y959654D01*
X1612496Y960100D01*
X1613247Y959706D01*
X1614679Y960152D01*
X1615074Y960903D01*
X1625201Y964056D01*
X1629556D01*
G02X1630088Y963524I0J-532D01*
G01Y962381D01*
G54D49*
X516898Y1435021D03*
X1026700Y1130200D03*
X1013231Y1094671D03*
X986500Y1118800D03*
G54D58*
X809631Y1305085D03*
Y1310085D03*
Y1315085D03*
Y1320085D03*
X810101Y1347591D03*
Y1352591D03*
Y1357591D03*
Y1362591D03*
X809880Y1385259D03*
Y1390259D03*
Y1395259D03*
Y1400259D03*
G54D67*
X1001687Y1111499D03*
G54D77*
G01X1113530Y569663D02*
X1114956D01*
G03X1115711Y570418I0J755D01*
G01Y571206D01*
G03X1114286Y572631I-1425J0D01*
G01X1077448D01*
G03X1077094Y572526I0J-649D01*
G01X1075459Y571464D01*
X1075315Y570786D01*
X1073679Y569724D01*
X1073001Y569868D01*
X1071366Y568806D01*
X1071222Y568128D01*
X1069586Y567066D01*
X1068909Y567210D01*
X1067273Y566148D01*
X1067129Y565470D01*
X1065494Y564408D01*
X1064816Y564552D01*
X1063180Y563490D01*
X1063036Y562813D01*
X1061401Y561751D01*
X1060723Y561895D01*
X985089Y512778D01*
X984945Y512100D01*
X983309Y511038D01*
X982632Y511182D01*
X980996Y510120D01*
X980852Y509442D01*
X979217Y508380D01*
X978539Y508524D01*
X976903Y507462D01*
X976759Y506784D01*
X975124Y505722D01*
X974446Y505866D01*
X972811Y504804D01*
X972667Y504126D01*
X971031Y503064D01*
X970353Y503208D01*
X924293Y473297D01*
X924149Y472619D01*
X922513Y471557D01*
X921836Y471701D01*
X920200Y470639D01*
X920056Y469962D01*
X918421Y468899D01*
X917743Y469044D01*
X916108Y467982D01*
X915963Y467304D01*
X914328Y466242D01*
X913650Y466386D01*
X912015Y465324D01*
X911871Y464646D01*
X910235Y463584D01*
X909610Y463716D01*
X889836Y450853D01*
X843324Y379226D01*
Y379224D01*
X843460Y378585D01*
X842367Y376903D01*
X841728Y376767D01*
X840666Y375131D01*
X840800Y374503D01*
X839699Y372808D01*
X839070Y372674D01*
X828877Y356976D01*
X823804Y333112D01*
Y295996D01*
G03X825131Y294669I1327J0D01*
G01X826031D01*
G03X826772Y295410I0J741D01*
G01Y296850D01*
G01X1119042Y569663D02*
X1117616D01*
G02X1116861Y570418I0J755D01*
G01Y571206D01*
G03X1114286Y573781I-2575J0D01*
G01X1076914D01*
X908930Y464693D01*
X909001D01*
X889004Y451685D01*
X842358Y379851D01*
X842359D01*
X827796Y357424D01*
X822654Y333233D01*
Y295996D01*
G03X825131Y293519I2477J0D01*
G01X826031D01*
G02X826772Y292778I0J-741D01*
G01Y291338D01*
G01X1099357Y569663D02*
X1100783D01*
G02X1101538Y568908I0J-755D01*
G02X1099325Y566695I-2213J0D01*
G01X1079061D01*
X1052411Y549362D01*
X1051789Y549494D01*
X1050154Y548431D01*
X1050022Y547808D01*
X1048387Y546745D01*
X1047765Y546877D01*
X1046130Y545814D01*
X1045998Y545191D01*
X932154Y471146D01*
X931532Y471278D01*
X929897Y470215D01*
X929765Y469592D01*
X928130Y468529D01*
X927508Y468661D01*
X925873Y467598D01*
X925741Y466975D01*
X924107Y465912D01*
X923484Y466044D01*
X921849Y464981D01*
X921718Y464358D01*
X894914Y446925D01*
X894915D01*
X837378Y360037D01*
X833657Y354308D01*
X829740Y335875D01*
Y309900D01*
G02X828700Y308842I-1040J-18D01*
G01X827513D01*
G02X826772Y309583I0J741D01*
G01Y311023D01*
G01X1104869Y569663D02*
X1103443D01*
G03X1102688Y568908I0J-755D01*
G02X1099325Y565545I-3363J0D01*
G01X1079403D01*
X1065819Y556710D01*
X1052236Y547875D01*
X895744Y446092D01*
X895743Y446090D01*
X838334Y359397D01*
X834738Y353860D01*
X830890Y335754D01*
Y309919D01*
G02X828700Y307692I-2190J-37D01*
G01X827513D01*
G03X826772Y306951I0J-741D01*
G01Y305512D01*
G01X1095420Y562576D02*
X1096846D01*
G02X1097601Y561821I0J-755D01*
G01Y561033D01*
G02X1096176Y559608I-1425J0D01*
G01X1079944D01*
X899990Y442756D01*
X898688Y440755D01*
X897520Y438959D01*
X895183Y435366D01*
X890508Y428180D01*
X889886Y428048D01*
X888822Y426413D01*
X888954Y425791D01*
X887891Y424156D01*
X887269Y424024D01*
X886206Y422389D01*
X886337Y421766D01*
X854604Y372980D01*
X853982Y372848D01*
X852918Y371213D01*
X853050Y370591D01*
X851987Y368956D01*
X851365Y368824D01*
X850302Y367190D01*
X850433Y366567D01*
X849212Y364689D01*
X848589Y364557D01*
X847526Y362923D01*
X847658Y362300D01*
X840494Y351286D01*
X836827Y336846D01*
Y305445D01*
G02X835500Y304118I-1327J0D01*
G01X834600D01*
G02X833859Y304859I0J741D01*
G01Y306299D01*
G01X1100932Y562576D02*
X1099506D01*
G03X1098751Y561821I0J-755D01*
G01Y561033D01*
G02X1096176Y558458I-2575J0D01*
G01X1080285D01*
X900821Y441924D01*
X841563Y350819D01*
X837977Y336700D01*
Y305445D01*
G02X835500Y302968I-2477J0D01*
G01X834600D01*
G03X833859Y302227I0J-741D01*
G01Y300787D01*
G01X1099357Y555490D02*
X1100783D01*
G02X1101538Y554735I0J-755D01*
G01Y553947D01*
G02X1100113Y552522I-1425J0D01*
G01X1082956D01*
X911562Y441209D01*
X910940Y441341D01*
X909304Y440279D01*
X909172Y439657D01*
X907537Y438594D01*
X906914Y438727D01*
X905279Y437665D01*
X905146Y437042D01*
X903511Y435980D01*
X849169Y352301D01*
X846907Y341660D01*
X846373Y341313D01*
X845968Y339406D01*
X846314Y338872D01*
X845909Y336965D01*
X845375Y336618D01*
X844970Y334711D01*
X845316Y334177D01*
X844911Y332270D01*
X844377Y331923D01*
X843972Y330016D01*
X844318Y329482D01*
X843913Y327575D01*
Y310169D01*
G02X842586Y308842I-1327J0D01*
G01X841686D01*
G02X840945Y309583I0J741D01*
G01Y311023D01*
G01X1104869Y555490D02*
X1103443D01*
G03X1102688Y554735I0J-755D01*
G01Y553947D01*
G02X1100113Y551372I-2575J0D01*
G01X1083297D01*
X904343Y435148D01*
X850250Y351853D01*
X845063Y327454D01*
Y310169D01*
G02X842586Y307692I-2477J0D01*
G01X841686D01*
G03X840945Y306951I0J-741D01*
G01Y305512D01*
G01X1095420Y548403D02*
X1096846D01*
G02X1097601Y547648I0J-755D01*
G01Y546860D01*
G02X1096176Y545435I-1425J0D01*
G01X1085001D01*
X916103Y435742D01*
X915481Y435874D01*
X913845Y434812D01*
X913713Y434190D01*
X912078Y433127D01*
X911455Y433260D01*
X909820Y432198D01*
X909687Y431575D01*
X908052Y430513D01*
X855439Y349497D01*
X854888Y346903D01*
X854355Y346557D01*
X853949Y344649D01*
X854296Y344116D01*
X853891Y342208D01*
X853357Y341861D01*
X852952Y339954D01*
X853299Y339420D01*
X852894Y337513D01*
X852360Y337166D01*
X851955Y335259D01*
X852302Y334725D01*
X851000Y328593D01*
Y305445D01*
G02X849673Y304118I-1327J0D01*
G01X848773D01*
G02X848032Y304859I0J741D01*
G01Y306299D01*
G01X1100932Y548403D02*
X1099506D01*
G03X1098751Y547648I0J-755D01*
G01Y546860D01*
G02X1096176Y544285I-2575J0D01*
G01X1085342D01*
X908884Y429681D01*
X856520Y349050D01*
Y349049D01*
X852150Y328472D01*
Y305445D01*
G02X849673Y302968I-2477J0D01*
G01X848773D01*
G03X848032Y302227I0J-741D01*
G01Y300787D01*
G01X1099357Y541317D02*
X1100783D01*
G02X1101538Y540562I0J-755D01*
G01Y539774D01*
G02X1100113Y538349I-1425J0D01*
G01X1085690D01*
X914321Y427062D01*
X912475Y424219D01*
X911852Y424087D01*
X910790Y422452D01*
X910923Y421829D01*
X909860Y420194D01*
X909238Y420061D01*
X908176Y418426D01*
X908308Y417803D01*
X863844Y349338D01*
X863439Y347431D01*
X862905Y347084D01*
X862499Y345177D01*
X862846Y344643D01*
X862441Y342735D01*
X861907Y342389D01*
X861502Y340481D01*
X861848Y339948D01*
X861443Y338040D01*
X860909Y337694D01*
X860504Y335786D01*
X860850Y335253D01*
X858084Y322236D01*
X858086Y322225D01*
Y310169D01*
G02X856759Y308842I-1327J0D01*
G01X855859D01*
G02X855118Y309583I0J741D01*
G01Y311023D01*
G01X1104869Y541317D02*
X1103443D01*
G03X1102688Y540562I0J-755D01*
G01Y539774D01*
G02X1100113Y537199I-2575J0D01*
G01X1086031D01*
X915153Y426230D01*
X864925Y348890D01*
X859236Y322124D01*
Y310169D01*
G02X856759Y307692I-2477J0D01*
G01X855859D01*
G03X855118Y306951I0J-741D01*
G01Y305512D01*
G01X1095420Y534230D02*
X1096846D01*
G02X1097601Y533475I0J-755D01*
G01Y532687D01*
G02X1096176Y531262I-1425J0D01*
G01X1086688D01*
X919378Y422610D01*
X903976Y398892D01*
X903354Y398760D01*
X902292Y397124D01*
X902424Y396502D01*
X901362Y394867D01*
X900740Y394734D01*
X899678Y393099D01*
X899810Y392476D01*
X898748Y390841D01*
X898126Y390709D01*
X897064Y389073D01*
X897196Y388451D01*
X874782Y353935D01*
X874160Y353803D01*
X873098Y352168D01*
X873230Y351545D01*
X872168Y349910D01*
X871546Y349777D01*
X870484Y348142D01*
X870616Y347519D01*
X869554Y345884D01*
X865173Y325263D01*
Y305445D01*
G02X863846Y304118I-1327J0D01*
G01X862946D01*
G02X862205Y304859I0J741D01*
G01Y306299D01*
G01X1100932Y534230D02*
X1099506D01*
G03X1098751Y533475I0J-755D01*
G01Y532687D01*
G02X1096176Y530112I-2575J0D01*
G01X1087029D01*
X920210Y421778D01*
X870635Y345436D01*
X866323Y325142D01*
Y305445D01*
G02X863846Y302968I-2477J0D01*
G01X862946D01*
G03X862205Y302227I0J-741D01*
G01Y300787D01*
G01X1099357Y527143D02*
X1100783D01*
G02X1101538Y526388I0J-755D01*
G01Y525600D01*
G02X1100113Y524175I-1425J0D01*
G01X1087762D01*
X924698Y418280D01*
X909527Y394919D01*
X908904Y394787D01*
X907842Y393152D01*
X907974Y392529D01*
X906912Y390894D01*
X906290Y390761D01*
X905228Y389126D01*
X905360Y388503D01*
X904298Y386868D01*
X903676Y386736D01*
X902614Y385100D01*
X902746Y384478D01*
X888930Y363205D01*
X888307Y363072D01*
X887245Y361437D01*
X887377Y360814D01*
X886315Y359179D01*
X885693Y359047D01*
X884631Y357411D01*
X884763Y356789D01*
X875041Y341819D01*
X872260Y328719D01*
Y310169D01*
G02X870933Y308842I-1327J0D01*
G01X870033D01*
G02X869292Y309583I0J741D01*
G01Y311023D01*
G01X1104869Y527143D02*
X1103443D01*
G03X1102688Y526388I0J-755D01*
G01Y525600D01*
G02X1100113Y523025I-2575J0D01*
G01X1088103D01*
X1006815Y470236D01*
X925530Y417448D01*
X876122Y341372D01*
X873410Y328598D01*
Y310169D01*
G02X870933Y307692I-2477J0D01*
G01X870033D01*
G03X869292Y306951I0J-741D01*
G01Y305512D01*
G01X1095420Y520057D02*
X1096846D01*
G02X1097601Y519302I0J-755D01*
G01Y517739D01*
X1096700Y516838D01*
X971416Y435478D01*
X970794Y435611D01*
X969158Y434549D01*
X969026Y433926D01*
X967390Y432864D01*
X966768Y432997D01*
X965133Y431934D01*
X965000Y431312D01*
X963365Y430250D01*
X962742Y430382D01*
X961107Y429320D01*
X960975Y428698D01*
X941653Y416149D01*
X941030Y416282D01*
X939395Y415220D01*
X939262Y414597D01*
X937627Y413535D01*
X937004Y413667D01*
X935369Y412605D01*
X935237Y411983D01*
X928437Y407567D01*
X879286Y331881D01*
Y305385D01*
G02X878019Y304118I-1267J0D01*
G01X877119D01*
G02X876378Y304859I0J741D01*
G01Y306299D01*
G01X1100932Y520057D02*
X1099506D01*
G03X1098751Y519302I0J-755D01*
G01Y517262D01*
X1097428Y515939D01*
X929269Y406735D01*
X880436Y331540D01*
Y305385D01*
G02X878019Y302968I-2417J0D01*
G01X877119D01*
G03X876378Y302227I0J-741D01*
G01Y300787D01*
G54D59*
X962648Y1101699D03*
X984534D03*
G54D68*
X1004640Y1117605D03*
X998734D03*
Y1105393D03*
X1004640D03*
G54D78*
G01X1056116Y697100D02*
X1056104Y697088D01*
Y681393D01*
X1055788Y681077D01*
Y681059D01*
X1055781Y681052D01*
Y663810D01*
X960468Y568497D01*
X927912D01*
X892821Y533406D01*
X880714D01*
X880713Y533407D01*
X879036D01*
X879035Y533408D01*
X874003D01*
X809119Y468524D01*
X790374D01*
X787971Y466121D01*
G01X791971D02*
X809580D01*
X874842Y531383D01*
X878196D01*
X878197Y531382D01*
X879874D01*
X879875Y531381D01*
X895102D01*
X930177Y566456D01*
X964012D01*
X1057806Y660250D01*
Y680213D01*
X1057826Y680233D01*
G01X1059927Y688329D02*
Y684381D01*
X1060985Y683323D01*
Y659309D01*
X966091Y564415D01*
X933649D01*
X898590Y529356D01*
X879035D01*
X879034Y529357D01*
X877358D01*
X877357Y529358D01*
X875681D01*
X810351Y464028D01*
X790078D01*
X787971Y461921D01*
G01X791971D02*
X811108D01*
X876519Y527332D01*
X878195D01*
X878196Y527331D01*
X899936D01*
X934995Y562390D01*
X966930D01*
X1064220Y659680D01*
Y683747D01*
X1064216Y683751D01*
G01X787971Y457721D02*
X790048Y459798D01*
X811849D01*
X877357Y525306D01*
X900862D01*
X918676Y543120D01*
Y543207D01*
X935834Y560365D01*
X967769D01*
X1067554Y660150D01*
Y694447D01*
G01X791971Y457721D02*
X812636D01*
X878196Y523281D01*
X901701D01*
X923179Y544759D01*
X951953D01*
X961160Y553966D01*
X972452D01*
X1071179Y652693D01*
Y682315D01*
G01X941456Y1182512D02*
X930097D01*
X902834Y1155249D01*
X799949D01*
X795100Y1150400D01*
G01X798920Y1150500D02*
X902482D01*
X929551Y1177569D01*
X951723D01*
G01X1038179Y413863D02*
X1024784Y400468D01*
Y400317D01*
X1023531Y399064D01*
X1023380D01*
X989571Y365255D01*
X976363D01*
X951751Y340643D01*
X916637D01*
X909236Y333242D01*
G01X1022646Y401202D02*
X988724Y367280D01*
X975524D01*
X950912Y342668D01*
X915717D01*
X906486Y333437D01*
Y330524D01*
G01X904725Y291338D02*
Y293544D01*
X900125Y298144D01*
Y317136D01*
X921607Y338618D01*
X952590D01*
X977202Y363230D01*
X990719D01*
X1071421Y443932D01*
G01X904725Y296850D02*
X904650D01*
X902200Y299300D01*
Y316347D01*
X922446Y336593D01*
X953429D01*
X978041Y361205D01*
X992166D01*
X1021469Y390508D01*
G01X904725Y305512D02*
Y307525D01*
X909226Y312026D01*
Y312589D01*
X909275Y312638D01*
Y315011D01*
X926564Y332300D01*
X1001800D01*
X1074279Y404779D01*
Y407249D01*
G01X904725Y311023D02*
X907200Y313498D01*
Y316160D01*
X925440Y334400D01*
X954100D01*
X978880Y359180D01*
X993620D01*
X1059563Y425123D01*
G01X897638Y306299D02*
X895300Y308637D01*
Y312383D01*
X896300Y313383D01*
Y326115D01*
X914878Y344693D01*
X949544D01*
X974451Y369600D01*
X988026D01*
X1020508Y402082D01*
Y402087D01*
X1021761Y403340D01*
X1021766D01*
X1047434Y429008D01*
G01X922800Y362400D02*
X924055Y363655D01*
Y364345D01*
X946829Y387119D01*
X970949D01*
X977047Y393217D01*
G01X922700Y358100D02*
X927500Y362900D01*
Y364000D01*
X947774Y384274D01*
X976412D01*
X996452Y404314D01*
G01X890552Y301181D02*
Y301348D01*
X888100Y303800D01*
Y325943D01*
X912526Y350369D01*
X925675D01*
X927509Y352203D01*
X927703D01*
X950843Y375343D01*
Y378827D01*
G01X1004412Y559568D02*
X991132Y546288D01*
X989017D01*
X982149Y539420D01*
Y534217D01*
X976560Y528628D01*
X946942D01*
X943947Y531623D01*
X928921D01*
X905360Y508062D01*
X883043D01*
X868281Y493300D01*
X867299D01*
G01Y497200D02*
X868397D01*
X881934Y510737D01*
X904251D01*
X927812Y534298D01*
X945056D01*
X948050Y531304D01*
X975452D01*
X979474Y535326D01*
Y540529D01*
X987908Y548963D01*
X990023D01*
X995316Y554256D01*
G01X873000Y494100D02*
X875572D01*
X884083Y502611D01*
X896476D01*
G01D02*
X905303D01*
X922525Y519833D01*
G01X929096Y517567D02*
X913276Y501747D01*
G01D02*
X906360Y494831D01*
X880731D01*
X873200Y487300D01*
G01X867299Y508600D02*
X870867D01*
X879811Y517544D01*
X903490D01*
X925594Y539648D01*
X947274D01*
X948443Y538479D01*
X948727D01*
X948728Y538480D01*
X959079D01*
X965575Y544976D01*
X975764D01*
X978415Y547627D01*
G01X968979Y542300D02*
X966683D01*
X960187Y535804D01*
X947334D01*
X946165Y536973D01*
X926703D01*
X904599Y514869D01*
X880920D01*
X870751Y504700D01*
X867299D01*
G01X982500Y1201000D02*
X979600Y1198100D01*
Y1194200D01*
X967912Y1182512D01*
X941456D01*
G01X982500Y1197000D02*
Y1193100D01*
X966969Y1177569D01*
X951723D01*
G01X1038179Y413863D02*
X1108416Y484100D01*
X1147487D01*
X1149964Y481623D01*
G01X1022646Y401202D02*
X1036041Y414597D01*
Y414748D01*
X1037294Y416001D01*
X1037445D01*
X1048314Y426870D01*
X1048319D01*
X1049572Y428123D01*
Y428128D01*
X1107569Y486125D01*
X1149875D01*
X1150900Y485100D01*
G01X1021469Y390508D02*
X1099084Y468123D01*
X1122123D01*
X1130100Y476100D01*
X1140036D01*
X1141382Y474754D01*
Y472056D01*
X1141400Y472038D01*
Y470190D01*
X1139590Y468380D01*
G01X1047434Y429008D02*
X1102677Y484251D01*
Y487116D01*
G01X1113530Y541317D02*
Y540060D01*
X1116620Y536970D01*
X1136560D01*
X1140025Y533505D01*
Y518971D01*
X1121254Y500200D01*
X1102130D01*
X1029440Y427510D01*
X1011340D01*
X977047Y393217D01*
G01X1119042Y541317D02*
Y543002D01*
X1121180Y545140D01*
X1138460D01*
X1143198Y540402D01*
Y518360D01*
X1122363Y497525D01*
X1103467D01*
X1030777Y424835D01*
X1016973D01*
X996452Y404314D01*
G01X1115105Y562576D02*
X1118009Y565480D01*
X1136569D01*
X1139784Y568695D01*
Y570631D01*
X1127143Y583272D01*
X1028116D01*
X1004412Y559568D01*
G01X1109593Y562576D02*
X1113069Y559100D01*
X1133973D01*
X1142459Y567586D01*
Y569522D01*
X1142460Y569523D01*
Y571739D01*
X1128252Y585947D01*
X1027007D01*
X995316Y554256D01*
G01X978415Y547627D02*
X987429Y556641D01*
X988562D01*
X1023218Y591297D01*
X1159297D01*
X1171700Y603700D01*
G01X1172500Y599700D02*
X1161422Y588622D01*
X1024327D01*
X989670Y553965D01*
X988537D01*
X976872Y542300D01*
X968979D01*
G01X1035526Y1455899D02*
Y1453536D01*
X1054284Y1434778D01*
Y1408577D01*
X1065915Y1396946D01*
X1071643D01*
X1075089Y1393500D01*
X1091000D01*
G01X1086646Y1396419D02*
X1075954D01*
X1072752Y1399621D01*
X1067024D01*
X1056959Y1409686D01*
Y1435887D01*
X1041176Y1451670D01*
Y1455500D01*
G01X1071421Y443932D02*
X1097812Y470323D01*
X1120323D01*
X1128125Y478125D01*
X1141275D01*
X1143420Y475980D01*
Y472900D01*
G01X1135410Y468380D02*
X1074279Y407249D01*
G01X1059563Y425123D02*
X1098551Y464111D01*
X1126601D01*
X1135310Y472820D01*
G01X1115105Y548403D02*
Y550125D01*
X1116170Y551190D01*
X1165690D01*
X1184500Y570000D01*
G01X1119042Y755490D02*
X1122152Y758600D01*
X1158018D01*
X1175723Y740895D01*
X1198184D01*
G01X1113530Y755490D02*
X1116044Y752976D01*
X1157255D01*
X1173536Y736695D01*
X1192158D01*
G01X1115105Y748403D02*
X1117603Y750901D01*
X1154899D01*
X1173305Y732495D01*
X1197842D01*
G01X1109593Y748403D02*
X1112091Y745905D01*
X1152891D01*
X1152906Y745890D01*
X1154246D01*
X1171841Y728295D01*
X1192853D01*
G01X1119042Y741317D02*
X1121555Y743830D01*
X1152102D01*
X1171837Y724095D01*
X1198213D01*
G01X1113530Y741317D02*
X1114493D01*
X1117760Y738050D01*
X1153988D01*
X1172143Y719895D01*
X1192568D01*
G01X1184500Y570000D02*
Y576000D01*
X1174000Y586500D01*
X1167000D01*
G01X1212587Y740895D02*
X1198184D01*
G01X1192158Y736695D02*
X1212587D01*
G01X1197842Y732495D02*
X1212587D01*
G01X1192853Y728295D02*
X1212587D01*
G01X1198213Y724095D02*
X1212587D01*
G01X1192568Y719895D02*
X1212587D01*
G54D69*
X1002671Y1117555D03*
X1000703D03*
Y1105443D03*
X1002671D03*
M02*
